FILE_TYPE = MACRO_DRAWING;
SET COLOR_WIRE YELLOW;
SET COLOR_PROP MONO;
SET COLOR_DOT WHITE;
SET COLOR_ARC YELLOW;
SET COLOR_BODY GREEN;
SET COLOR_NOTE MONO;
SET PROP_DISPLAY VALUE;
SET PAGE_NUMBER P150;
FORCEADD OFFPAGE..2
(850 200);
FORCEPROP 2 LAST $XR0 146 
J 0
(1039 200);
DISPLAY 0.638298 (1039 200);
PAINT MONO (1039 200);
FORCEPROP 2 LAST $XR1 162 
J 0
(1159 200);
DISPLAY 0.638298 (1159 200);
PAINT MONO (1159 200);
FORCEPROP 2 LAST $XR2 246 
J 0
(1279 200);
DISPLAY 0.638298 (1279 200);
PAINT MONO (1279 200);
FORCEPROP 2 LAST PATH I140
J 0
(1175 250);
DISPLAY 1.021277 (1175 250);
PAINT ORANGE (1175 250);
DISPLAY INVISIBLE (1175 250);
FORCEPROP 2 LAST CDS_LIB mstr_standard
J 0
(850 200);
PAINT ORANGE (850 200);
DISPLAY INVISIBLE (850 200);
FORCEPROP 1 LAST OFFPAGE TRUE
J 0
(1175 75);
DISPLAY 0.872340 (1175 75);
PAINT GREEN (1175 75);
DISPLAY INVISIBLE (1175 75);
FORCEPROP 1 LAST COMMENT_BODY TRUE
J 0
(805 105);
DISPLAY 0.872340 (805 105);
PAINT GREEN (805 105);
DISPLAY INVISIBLE (805 105);
FORCEADD OFFPAGE..2
(850 0);
FORCEPROP 2 LAST $XR0 146 
J 0
(1039 0);
DISPLAY 0.638298 (1039 0);
PAINT MONO (1039 0);
FORCEPROP 2 LAST $XR1 162 
J 0
(1159 0);
DISPLAY 0.638298 (1159 0);
PAINT MONO (1159 0);
FORCEPROP 2 LAST $XR2 246 
J 0
(1279 0);
DISPLAY 0.638298 (1279 0);
PAINT MONO (1279 0);
FORCEPROP 2 LAST CDS_LIB mstr_standard
J 0
(850 0);
PAINT ORANGE (850 0);
DISPLAY INVISIBLE (850 0);
FORCEPROP 2 LAST PATH I141
J 0
(1175 50);
DISPLAY 1.021277 (1175 50);
PAINT ORANGE (1175 50);
DISPLAY INVISIBLE (1175 50);
FORCEPROP 1 LAST OFFPAGE TRUE
J 0
(1175 -125);
DISPLAY 0.872340 (1175 -125);
PAINT GREEN (1175 -125);
DISPLAY INVISIBLE (1175 -125);
FORCEPROP 1 LAST COMMENT_BODY TRUE
J 0
(805 -95);
DISPLAY 0.872340 (805 -95);
PAINT GREEN (805 -95);
DISPLAY INVISIBLE (805 -95);
FORCEADD OFFPAGE..4
(850 -200);
FORCEPROP 2 LAST $XR0 162 
J 0
(1036 -200);
DISPLAY 0.638298 (1036 -200);
PAINT MONO (1036 -200);
FORCEPROP 2 LAST $XR1 246 
J 0
(1156 -200);
DISPLAY 0.638298 (1156 -200);
PAINT MONO (1156 -200);
FORCEPROP 2 LAST $XR2 146 
J 0
(1276 -200);
DISPLAY 0.638298 (1276 -200);
PAINT MONO (1276 -200);
FORCEPROP 2 LAST CDS_LIB mstr_standard
J 0
(850 -200);
PAINT ORANGE (850 -200);
DISPLAY INVISIBLE (850 -200);
FORCEPROP 2 LAST PATH I142
J 0
(1175 -150);
DISPLAY 1.021277 (1175 -150);
PAINT ORANGE (1175 -150);
DISPLAY INVISIBLE (1175 -150);
FORCEPROP 1 LAST OFFPAGE TRUE
J 0
(1175 -325);
DISPLAY 0.872340 (1175 -325);
PAINT GREEN (1175 -325);
DISPLAY INVISIBLE (1175 -325);
FORCEPROP 1 LAST COMMENT_BODY TRUE
J 0
(825 -300);
DISPLAY 0.872340 (825 -300);
PAINT GREEN (825 -300);
DISPLAY INVISIBLE (825 -300);
FORCEADD RES..1
(-600 200);
FORCEPROP 1 LAST LOCATION R25W95
J 0
(-850 250);
DISPLAY 0.617021 (-850 250);
PAINT AQUA (-850 250);
FORCEPROP 1 LAST MATERIAL CHIP
J 0
(-850 200);
DISPLAY 0.617021 (-850 200);
PAINT SKYBLUE (-850 200);
FORCEPROP 1 LASTPIN (-500 200) $PN 2
J 0
(-538 212);
DISPLAY 0.787234 (-538 212);
PAINT ORANGE (-538 212);
FORCEPROP 1 LAST TOLERANCE 1%
J 0
(-525 250);
DISPLAY 0.617021 (-525 250);
PAINT SKYBLUE (-525 250);
FORCEPROP 1 LASTPIN (-700 200) $PN 1
J 0
(-688 212);
DISPLAY 0.787234 (-688 212);
PAINT ORANGE (-688 212);
FORCEPROP 1 LAST PART_NUMBER G21796-072
J 0
(-450 200);
DISPLAY 0.617021 (-450 200);
PAINT BLUE (-450 200);
FORCEPROP 1 LAST WATTAGE 1/16W
J 0
(-450 250);
DISPLAY 0.617021 (-450 250);
PAINT SKYBLUE (-450 250);
FORCEPROP 1 LAST VALUE 4.75K
J 0
(-650 250);
DISPLAY 0.617021 (-650 250);
PAINT SKYBLUE (-650 250);
FORCEPROP 1 LAST PACK_TYPE 0402
J 0
(-200 200);
DISPLAY 0.617021 (-200 200);
PAINT SKYBLUE (-200 200);
FORCEPROP 0 LAST SEC 1
J 0
(-650 300);
PAINT MONO (-650 300);
DISPLAY INVISIBLE (-650 300);
FORCEPROP 2 LAST SEC_TYPE 0402
J 0
(-650 400);
DISPLAY 1.021277 (-650 400);
PAINT ORANGE (-650 400);
DISPLAY INVISIBLE (-650 400);
FORCEPROP 1 LAST PATH I144
J 0
(-650 350);
DISPLAY 0.978723 (-650 350);
PAINT WHITE (-650 350);
DISPLAY INVISIBLE (-650 350);
FORCEPROP 0 LAST CDS_LOCATION R25W95
J 0
(-650 300);
PAINT MONO (-650 300);
DISPLAY INVISIBLE (-650 300);
FORCEPROP 2 LAST ROOM BMC
J 0
(-650 300);
DISPLAY 1.021277 (-650 300);
PAINT ORANGE (-650 300);
DISPLAY INVISIBLE (-650 300);
FORCEPROP 2 LAST BOM_COST SM_CONTROLLER
J 0
(-650 350);
DISPLAY 1.021277 (-650 350);
PAINT ORANGE (-650 350);
DISPLAY INVISIBLE (-650 350);
FORCEPROP 2 LAST CDS_LIB mstr_discrete
J 0
(-600 200);
PAINT MONO (-600 200);
DISPLAY INVISIBLE (-600 200);
FORCEADD RES..1
(-600 0);
FORCEPROP 1 LAST TOLERANCE 1%
J 0
(-525 50);
DISPLAY 0.617021 (-525 50);
PAINT SKYBLUE (-525 50);
FORCEPROP 1 LAST VALUE 4.75K
J 0
(-650 50);
DISPLAY 0.617021 (-650 50);
PAINT SKYBLUE (-650 50);
FORCEPROP 1 LAST MATERIAL CHIP
J 0
(-850 0);
DISPLAY 0.617021 (-850 0);
PAINT SKYBLUE (-850 0);
FORCEPROP 1 LASTPIN (-500 0) $PN 2
J 0
(-538 12);
DISPLAY 0.787234 (-538 12);
PAINT ORANGE (-538 12);
FORCEPROP 1 LASTPIN (-700 0) $PN 1
J 0
(-688 12);
DISPLAY 0.787234 (-688 12);
PAINT ORANGE (-688 12);
FORCEPROP 1 LAST PART_NUMBER G21796-072
J 0
(-450 0);
DISPLAY 0.617021 (-450 0);
PAINT BLUE (-450 0);
FORCEPROP 1 LAST WATTAGE 1/16W
J 0
(-450 50);
DISPLAY 0.617021 (-450 50);
PAINT SKYBLUE (-450 50);
FORCEPROP 1 LAST PACK_TYPE 0402
J 0
(-200 0);
DISPLAY 0.617021 (-200 0);
PAINT SKYBLUE (-200 0);
FORCEPROP 1 LAST LOCATION R25W96
J 0
(-850 50);
DISPLAY 0.617021 (-850 50);
PAINT AQUA (-850 50);
FORCEPROP 2 LAST SEC_TYPE 0402
J 0
(-650 200);
DISPLAY 1.021277 (-650 200);
PAINT ORANGE (-650 200);
DISPLAY INVISIBLE (-650 200);
FORCEPROP 0 LAST SEC 1
J 0
(-650 100);
PAINT MONO (-650 100);
DISPLAY INVISIBLE (-650 100);
FORCEPROP 2 LAST ROOM BMC
J 0
(-650 100);
DISPLAY 1.021277 (-650 100);
PAINT ORANGE (-650 100);
DISPLAY INVISIBLE (-650 100);
FORCEPROP 2 LAST BOM_COST SM_CONTROLLER
J 0
(-650 150);
DISPLAY 1.021277 (-650 150);
PAINT ORANGE (-650 150);
DISPLAY INVISIBLE (-650 150);
FORCEPROP 2 LAST CDS_LIB mstr_discrete
J 0
(-600 0);
PAINT MONO (-600 0);
DISPLAY INVISIBLE (-600 0);
FORCEPROP 0 LAST CDS_LOCATION R25W96
J 0
(-650 100);
PAINT MONO (-650 100);
DISPLAY INVISIBLE (-650 100);
FORCEPROP 1 LAST PATH I145
J 0
(-650 150);
DISPLAY 0.978723 (-650 150);
PAINT WHITE (-650 150);
DISPLAY INVISIBLE (-650 150);
FORCEADD RES..1
(-600 -200);
FORCEPROP 1 LAST WATTAGE 1/16W
J 2
(-325 -150);
DISPLAY 0.617021 (-325 -150);
PAINT SKYBLUE (-325 -150);
FORCEPROP 1 LAST PART_NUMBER G21796-072
J 0
(-450 -200);
DISPLAY 0.617021 (-450 -200);
PAINT BLUE (-450 -200);
FORCEPROP 1 LAST TOLERANCE 1%
J 0
(-525 -150);
DISPLAY 0.617021 (-525 -150);
PAINT SKYBLUE (-525 -150);
FORCEPROP 1 LAST VALUE 4.75K
J 2
(-550 -150);
DISPLAY 0.617021 (-550 -150);
PAINT SKYBLUE (-550 -150);
FORCEPROP 1 LASTPIN (-500 -200) $PN 2
J 0
(-538 -188);
DISPLAY 0.787234 (-538 -188);
PAINT ORANGE (-538 -188);
FORCEPROP 1 LAST LOCATION R25W97
J 0
(-850 -150);
DISPLAY 0.617021 (-850 -150);
PAINT AQUA (-850 -150);
FORCEPROP 1 LAST MATERIAL EMPTY
J 0
(-850 -200);
DISPLAY 0.617021 (-850 -200);
PAINT RED (-850 -200);
FORCEPROP 1 LASTPIN (-700 -200) $PN 1
J 0
(-688 -188);
DISPLAY 0.787234 (-688 -188);
PAINT ORANGE (-688 -188);
FORCEPROP 1 LAST PACK_TYPE 0402
J 0
(-200 -200);
DISPLAY 0.617021 (-200 -200);
PAINT SKYBLUE (-200 -200);
FORCEPROP 2 LAST ROOM BMC
J 0
(-650 -100);
DISPLAY 1.021277 (-650 -100);
PAINT ORANGE (-650 -100);
DISPLAY INVISIBLE (-650 -100);
FORCEPROP 2 LAST BOM_COST SM_CONTROLLER
J 0
(-650 -50);
DISPLAY 1.021277 (-650 -50);
PAINT ORANGE (-650 -50);
DISPLAY INVISIBLE (-650 -50);
FORCEPROP 2 LAST SEC 1
J 0
(-650 0);
PAINT MONO (-650 0);
DISPLAY INVISIBLE (-650 0);
FORCEPROP 2 LAST SEC_TYPE 0402
J 0
(-650 0);
DISPLAY 1.021277 (-650 0);
PAINT ORANGE (-650 0);
DISPLAY INVISIBLE (-650 0);
FORCEPROP 2 LAST CDS_LIB mstr_discrete
J 0
(-600 -200);
PAINT ORANGE (-600 -200);
DISPLAY INVISIBLE (-600 -200);
FORCEPROP 2 LAST CDS_LOCATION R25W97
J 0
(-650 -150);
DISPLAY 0.617021 (-650 -150);
PAINT AQUA (-650 -150);
DISPLAY INVISIBLE (-650 -150);
FORCEPROP 1 LAST PATH I146
J 0
(-650 -50);
DISPLAY 0.978723 (-650 -50);
PAINT WHITE (-650 -50);
DISPLAY INVISIBLE (-650 -50);
FORCEADD P3V3_STBY..1
(-1000 550);
FORCEPROP 3 LASTPIN (-1000 500) SIG_NAME P3V3_STBY\g
J 0
(-990 510);
DISPLAY 0.659574 (-990 510);
PAINT MONO (-990 510);
DISPLAY INVISIBLE (-990 510);
FORCEPROP 2 LAST CDS_LIB mstr_symbols
J 0
(-1000 550);
PAINT ORANGE (-1000 550);
DISPLAY INVISIBLE (-1000 550);
FORCEPROP 1 LAST VOLTAGE 3.3V
J 0
(-1045 507);
DISPLAY 0.340426 (-1045 507);
PAINT SKYBLUE (-1045 507);
DISPLAY INVISIBLE (-1045 507);
FORCEPROP 1 LAST SIZE 1B
J 0
(-955 572);
DISPLAY 0.340426 (-955 572);
PAINT GREEN (-955 572);
DISPLAY INVISIBLE (-955 572);
FORCEPROP 1 LAST PATH I147
J 0
(-955 552);
DISPLAY 0.340426 (-955 552);
PAINT GREEN (-955 552);
DISPLAY INVISIBLE (-955 552);
FORCEPROP 1 LAST BODY_TYPE PLUMBING
J 0
(-1045 507);
DISPLAY 0.340426 (-1045 507);
PAINT GREEN (-1045 507);
DISPLAY INVISIBLE (-1045 507);
FORCEPROP 1 LAST HDL_POWER P3V3_STBY
J 0
(-1300 425);
DISPLAY 0.872340 (-1300 425);
PAINT ORANGE (-1300 425);
DISPLAY INVISIBLE (-1300 425);
FORCEADD OFFPAGE..2
(850 -400);
FORCEPROP 2 LAST $XR0 144 
J 0
(1039 -400);
DISPLAY 0.638298 (1039 -400);
PAINT MONO (1039 -400);
FORCEPROP 2 LAST CDS_LIB mstr_standard
J 0
(850 -400);
PAINT MONO (850 -400);
DISPLAY INVISIBLE (850 -400);
FORCEPROP 2 LAST PATH I155
J 0
(1175 -350);
DISPLAY 1.021277 (1175 -350);
PAINT ORANGE (1175 -350);
DISPLAY INVISIBLE (1175 -350);
FORCEPROP 1 LAST OFFPAGE TRUE
J 0
(1175 -525);
DISPLAY 0.872340 (1175 -525);
PAINT GREEN (1175 -525);
DISPLAY INVISIBLE (1175 -525);
FORCEPROP 1 LAST COMMENT_BODY TRUE
J 0
(805 -495);
DISPLAY 0.872340 (805 -495);
PAINT GREEN (805 -495);
DISPLAY INVISIBLE (805 -495);
FORCEADD OFFPAGE..2
(850 -1100);
FORCEPROP 2 LAST $XR0 147 
J 0
(1039 -1100);
DISPLAY 0.638298 (1039 -1100);
PAINT MONO (1039 -1100);
FORCEPROP 2 LAST $XR1 186 
J 0
(1159 -1100);
DISPLAY 0.638298 (1159 -1100);
PAINT MONO (1159 -1100);
FORCEPROP 2 LAST PATH I156
J 0
(1175 -1050);
DISPLAY 1.021277 (1175 -1050);
PAINT ORANGE (1175 -1050);
DISPLAY INVISIBLE (1175 -1050);
FORCEPROP 2 LAST CDS_LIB mstr_standard
J 0
(850 -1100);
PAINT MONO (850 -1100);
DISPLAY INVISIBLE (850 -1100);
FORCEPROP 1 LAST OFFPAGE TRUE
J 0
(1175 -1225);
DISPLAY 0.872340 (1175 -1225);
PAINT GREEN (1175 -1225);
DISPLAY INVISIBLE (1175 -1225);
FORCEPROP 1 LAST COMMENT_BODY TRUE
J 0
(805 -1195);
DISPLAY 0.872340 (805 -1195);
PAINT GREEN (805 -1195);
DISPLAY INVISIBLE (805 -1195);
FORCEADD OFFPAGE..2
(850 -1900);
FORCEPROP 2 LAST $XR0 147 
J 0
(1039 -1900);
DISPLAY 0.638298 (1039 -1900);
PAINT MONO (1039 -1900);
FORCEPROP 2 LAST CDS_LIB mstr_standard
J 0
(850 -1900);
PAINT MONO (850 -1900);
DISPLAY INVISIBLE (850 -1900);
FORCEPROP 2 LAST PATH I157
J 0
(1050 -1850);
DISPLAY 1.021277 (1050 -1850);
PAINT ORANGE (1050 -1850);
DISPLAY INVISIBLE (1050 -1850);
FORCEPROP 1 LAST OFFPAGE TRUE
J 0
(1175 -2025);
DISPLAY 0.872340 (1175 -2025);
PAINT GREEN (1175 -2025);
DISPLAY INVISIBLE (1175 -2025);
FORCEPROP 1 LAST COMMENT_BODY TRUE
J 0
(805 -1995);
DISPLAY 0.872340 (805 -1995);
PAINT GREEN (805 -1995);
DISPLAY INVISIBLE (805 -1995);
FORCEADD OFFPAGE..2
(850 -2100);
FORCEPROP 2 LAST $XR0 147 
J 0
(1039 -2100);
DISPLAY 0.638298 (1039 -2100);
PAINT MONO (1039 -2100);
FORCEPROP 2 LAST PATH I158
J 0
(1050 -2050);
DISPLAY 1.021277 (1050 -2050);
PAINT ORANGE (1050 -2050);
DISPLAY INVISIBLE (1050 -2050);
FORCEPROP 2 LAST CDS_LIB mstr_standard
J 0
(850 -2100);
PAINT ORANGE (850 -2100);
DISPLAY INVISIBLE (850 -2100);
FORCEPROP 1 LAST OFFPAGE TRUE
J 0
(1175 -2225);
DISPLAY 0.872340 (1175 -2225);
PAINT GREEN (1175 -2225);
DISPLAY INVISIBLE (1175 -2225);
FORCEPROP 1 LAST COMMENT_BODY TRUE
J 0
(805 -2195);
DISPLAY 0.872340 (805 -2195);
PAINT GREEN (805 -2195);
DISPLAY INVISIBLE (805 -2195);
FORCEADD OFFPAGE..2
(850 -1500);
FORCEPROP 2 LAST $XR0 139 
J 0
(1039 -1500);
DISPLAY 0.638298 (1039 -1500);
PAINT MONO (1039 -1500);
FORCEPROP 2 LAST $XR1 147 
J 0
(1159 -1500);
DISPLAY 0.638298 (1159 -1500);
PAINT MONO (1159 -1500);
FORCEPROP 2 LAST $XR2 121 
J 0
(1279 -1500);
DISPLAY 0.638298 (1279 -1500);
PAINT MONO (1279 -1500);
FORCEPROP 2 LAST CDS_LIB mstr_standard
J 0
(850 -1500);
PAINT MONO (850 -1500);
DISPLAY INVISIBLE (850 -1500);
FORCEPROP 2 LAST PATH I161
J 0
(1300 -1450);
DISPLAY 1.021277 (1300 -1450);
PAINT ORANGE (1300 -1450);
DISPLAY INVISIBLE (1300 -1450);
FORCEPROP 1 LAST OFFPAGE TRUE
J 0
(1175 -1625);
DISPLAY 0.872340 (1175 -1625);
PAINT GREEN (1175 -1625);
DISPLAY INVISIBLE (1175 -1625);
FORCEPROP 1 LAST COMMENT_BODY TRUE
J 0
(805 -1595);
DISPLAY 0.872340 (805 -1595);
PAINT GREEN (805 -1595);
DISPLAY INVISIBLE (805 -1595);
FORCEADD OFFPAGE..2
(850 -650);
FORCEPROP 2 LAST $XR0 145 
J 0
(1039 -650);
DISPLAY 0.638298 (1039 -650);
PAINT MONO (1039 -650);
FORCEPROP 2 LAST $XR1 190 
J 0
(1159 -650);
DISPLAY 0.638298 (1159 -650);
PAINT MONO (1159 -650);
FORCEPROP 2 LAST $XR2 158 
J 0
(1279 -650);
DISPLAY 0.638298 (1279 -650);
PAINT MONO (1279 -650);
FORCEPROP 2 LAST CDS_LIB mstr_standard
J 0
(850 -650);
PAINT MONO (850 -650);
DISPLAY INVISIBLE (850 -650);
FORCEPROP 2 LAST PATH I166
J 0
(1050 -575);
DISPLAY 1.021277 (1050 -575);
PAINT ORANGE (1050 -575);
DISPLAY INVISIBLE (1050 -575);
FORCEPROP 1 LAST OFFPAGE TRUE
J 0
(1175 -775);
DISPLAY 0.872340 (1175 -775);
PAINT GREEN (1175 -775);
DISPLAY INVISIBLE (1175 -775);
FORCEPROP 1 LAST COMMENT_BODY TRUE
J 0
(805 -745);
DISPLAY 0.872340 (805 -745);
PAINT GREEN (805 -745);
DISPLAY INVISIBLE (805 -745);
FORCEADD RES..1
(-600 -1100);
FORCEPROP 1 LAST WATTAGE 1/16W
J 2
(-325 -1050);
DISPLAY 0.617021 (-325 -1050);
PAINT SKYBLUE (-325 -1050);
FORCEPROP 1 LAST PART_NUMBER G21796-072
J 0
(-450 -1100);
DISPLAY 0.617021 (-450 -1100);
PAINT BLUE (-450 -1100);
FORCEPROP 1 LASTPIN (-700 -1100) $PN 1
J 0
(-688 -1088);
DISPLAY 0.787234 (-688 -1088);
PAINT ORANGE (-688 -1088);
FORCEPROP 1 LAST TOLERANCE 1%
J 0
(-525 -1050);
DISPLAY 0.617021 (-525 -1050);
PAINT SKYBLUE (-525 -1050);
FORCEPROP 1 LAST VALUE 4.75K
J 2
(-550 -1050);
DISPLAY 0.617021 (-550 -1050);
PAINT SKYBLUE (-550 -1050);
FORCEPROP 1 LASTPIN (-500 -1100) $PN 2
J 0
(-538 -1088);
DISPLAY 0.787234 (-538 -1088);
PAINT ORANGE (-538 -1088);
FORCEPROP 1 LAST PACK_TYPE 0402
J 0
(-200 -1100);
DISPLAY 0.617021 (-200 -1100);
PAINT SKYBLUE (-200 -1100);
FORCEPROP 1 LAST MATERIAL EMPTY
J 0
(-850 -1100);
DISPLAY 0.617021 (-850 -1100);
PAINT RED (-850 -1100);
FORCEPROP 1 LAST LOCATION R25W106
J 0
(-850 -1050);
DISPLAY 0.617021 (-850 -1050);
PAINT AQUA (-850 -1050);
FORCEPROP 1 LAST PATH I175
J 0
(-650 -950);
DISPLAY 0.978723 (-650 -950);
PAINT WHITE (-650 -950);
DISPLAY INVISIBLE (-650 -950);
FORCEPROP 2 LAST BOM_COST SM_CONTROLLER
J 0
(-650 -950);
DISPLAY 1.021277 (-650 -950);
PAINT ORANGE (-650 -950);
DISPLAY INVISIBLE (-650 -950);
FORCEPROP 2 LAST ROOM BMC
J 0
(-650 -1000);
DISPLAY 1.021277 (-650 -1000);
PAINT ORANGE (-650 -1000);
DISPLAY INVISIBLE (-650 -1000);
FORCEPROP 2 LAST CDS_LIB mstr_discrete
J 0
(-600 -1100);
PAINT ORANGE (-600 -1100);
DISPLAY INVISIBLE (-600 -1100);
FORCEPROP 2 LAST CDS_LOCATION R25W106
J 0
(-650 -1050);
DISPLAY 0.617021 (-650 -1050);
PAINT AQUA (-650 -1050);
DISPLAY INVISIBLE (-650 -1050);
FORCEPROP 2 LAST SEC 1
J 0
(-650 -900);
PAINT MONO (-650 -900);
DISPLAY INVISIBLE (-650 -900);
FORCEPROP 2 LAST SEC_TYPE 0402
J 0
(-650 -900);
DISPLAY 1.021277 (-650 -900);
PAINT ORANGE (-650 -900);
DISPLAY INVISIBLE (-650 -900);
FORCEADD RES..1
(-600 -1500);
FORCEPROP 1 LAST PACK_TYPE 0402
J 0
(-200 -1500);
DISPLAY 0.617021 (-200 -1500);
PAINT SKYBLUE (-200 -1500);
FORCEPROP 1 LAST TOLERANCE 1%
J 0
(-525 -1450);
DISPLAY 0.617021 (-525 -1450);
PAINT SKYBLUE (-525 -1450);
FORCEPROP 1 LAST WATTAGE 1/16W
J 2
(-325 -1450);
DISPLAY 0.617021 (-325 -1450);
PAINT SKYBLUE (-325 -1450);
FORCEPROP 1 LAST VALUE 4.75K
J 2
(-550 -1450);
DISPLAY 0.617021 (-550 -1450);
PAINT SKYBLUE (-550 -1450);
FORCEPROP 1 LAST LOCATION R25W111
J 0
(-850 -1450);
DISPLAY 0.617021 (-850 -1450);
PAINT AQUA (-850 -1450);
FORCEPROP 1 LASTPIN (-500 -1500) $PN 2
J 0
(-538 -1488);
DISPLAY 0.787234 (-538 -1488);
PAINT ORANGE (-538 -1488);
FORCEPROP 1 LASTPIN (-700 -1500) $PN 1
J 0
(-688 -1488);
DISPLAY 0.787234 (-688 -1488);
PAINT ORANGE (-688 -1488);
FORCEPROP 1 LAST MATERIAL EMPTY
J 0
(-850 -1500);
DISPLAY 0.617021 (-850 -1500);
PAINT RED (-850 -1500);
FORCEPROP 1 LAST PART_NUMBER G21796-072
J 0
(-450 -1500);
DISPLAY 0.617021 (-450 -1500);
PAINT BLUE (-450 -1500);
FORCEPROP 1 LAST PATH I180
J 0
(-650 -1350);
DISPLAY 0.978723 (-650 -1350);
PAINT WHITE (-650 -1350);
DISPLAY INVISIBLE (-650 -1350);
FORCEPROP 2 LAST BOM_COST SM_CONTROLLER
J 0
(-650 -1350);
DISPLAY 1.021277 (-650 -1350);
PAINT ORANGE (-650 -1350);
DISPLAY INVISIBLE (-650 -1350);
FORCEPROP 2 LAST ROOM BMC
J 0
(-650 -1400);
DISPLAY 1.021277 (-650 -1400);
PAINT ORANGE (-650 -1400);
DISPLAY INVISIBLE (-650 -1400);
FORCEPROP 2 LAST CDS_LIB mstr_discrete
J 0
(-600 -1500);
PAINT ORANGE (-600 -1500);
DISPLAY INVISIBLE (-600 -1500);
FORCEPROP 2 LAST CDS_LOCATION R25W111
J 0
(-650 -1450);
DISPLAY 0.617021 (-650 -1450);
PAINT AQUA (-650 -1450);
DISPLAY INVISIBLE (-650 -1450);
FORCEPROP 2 LAST SEC 1
J 0
(-650 -1300);
PAINT MONO (-650 -1300);
DISPLAY INVISIBLE (-650 -1300);
FORCEPROP 2 LAST SEC_TYPE 0402
J 0
(-650 -1300);
DISPLAY 1.021277 (-650 -1300);
PAINT ORANGE (-650 -1300);
DISPLAY INVISIBLE (-650 -1300);
FORCEADD GND..1
(-900 -950);
FORCEPROP 3 LASTPIN (-900 -900) SIG_NAME GND\g
J 0
(-890 -890);
DISPLAY 0.659574 (-890 -890);
PAINT MONO (-890 -890);
DISPLAY INVISIBLE (-890 -890);
FORCEPROP 1 LAST PATH I186
J 0
(-825 -950);
DISPLAY 0.872340 (-825 -950);
PAINT AQUA (-825 -950);
DISPLAY INVISIBLE (-825 -950);
FORCEPROP 1 LAST VOLTAGE 0.0V
J 0
(-945 -993);
DISPLAY 0.340426 (-945 -993);
PAINT GREEN (-945 -993);
DISPLAY INVISIBLE (-945 -993);
FORCEPROP 1 LAST SIZE 1B
J 0
(-825 -1000);
DISPLAY 0.872340 (-825 -1000);
PAINT AQUA (-825 -1000);
DISPLAY INVISIBLE (-825 -1000);
FORCEPROP 2 LAST CDS_LIB mstr_symbols
J 0
(-900 -950);
PAINT MONO (-900 -950);
DISPLAY INVISIBLE (-900 -950);
FORCEPROP 1 LAST BODY_TYPE PLUMBING
J 0
(-945 -993);
DISPLAY 0.340426 (-945 -993);
PAINT GREEN (-945 -993);
DISPLAY INVISIBLE (-945 -993);
FORCEPROP 1 LAST HDL_POWER GND
J 0
(-900 -800);
DISPLAY 0.872340 (-900 -800);
PAINT GREEN (-900 -800);
DISPLAY INVISIBLE (-900 -800);
FORCEADD RES..2
R 1
(-600 -850);
FORCEPROP 1 LASTPIN (-700 -850) $PN 1
J 0
(-712 -845);
DISPLAY 0.617021 (-712 -845);
PAINT ORANGE (-712 -845);
FORCEPROP 1 LAST LOCATION R25W116
J 0
(-850 -780);
DISPLAY 0.617021 (-850 -780);
PAINT AQUA (-850 -780);
FORCEPROP 1 LAST MATERIAL EMPTY
J 0
(-850 -835);
DISPLAY 0.617021 (-850 -835);
PAINT RED (-850 -835);
FORCEPROP 1 LASTPIN (-500 -850) $PN 2
J 0
(-510 -845);
DISPLAY 0.617021 (-510 -845);
PAINT ORANGE (-510 -845);
FORCEPROP 1 LAST VALUE 3.32K
J 0
(-650 -805);
DISPLAY 0.617021 (-650 -805);
PAINT SKYBLUE (-650 -805);
FORCEPROP 1 LAST TOLERANCE 1%
J 0
(-525 -805);
DISPLAY 0.617021 (-525 -805);
PAINT SKYBLUE (-525 -805);
FORCEPROP 1 LAST WATTAGE 1/16W
J 0
(-450 -785);
DISPLAY 0.617021 (-450 -785);
PAINT SKYBLUE (-450 -785);
FORCEPROP 1 LAST PART_NUMBER G21796-027
J 0
(-450 -835);
DISPLAY 0.617021 (-450 -835);
PAINT BLUE (-450 -835);
FORCEPROP 1 LAST PACK_TYPE 0402
J 0
(-200 -835);
DISPLAY 0.617021 (-200 -835);
PAINT SKYBLUE (-200 -835);
FORCEPROP 2 LAST CDS_LIB mstr_discrete
R 1
J 0
(-600 -850);
PAINT ORANGE (-600 -850);
DISPLAY INVISIBLE (-600 -850);
FORCEPROP 2 LAST ROOM NIC_SPRV
R 1
J 0
(-775 -800);
DISPLAY 1.021277 (-775 -800);
PAINT ORANGE (-775 -800);
DISPLAY INVISIBLE (-775 -800);
FORCEPROP 2 LAST BOM_COST NT_GBE_BASE
R 1
J 0
(-825 -800);
DISPLAY 1.021277 (-825 -800);
PAINT ORANGE (-825 -800);
DISPLAY INVISIBLE (-825 -800);
FORCEPROP 2 LAST SEC_TYPE 0402
R 1
J 0
(-825 -800);
DISPLAY 1.021277 (-825 -800);
PAINT ORANGE (-825 -800);
DISPLAY INVISIBLE (-825 -800);
FORCEPROP 2 LAST SEC 1
R 1
J 0
(-825 -800);
PAINT MONO (-825 -800);
DISPLAY INVISIBLE (-825 -800);
FORCEPROP 1 LAST PATH I189
R 1
J 0
(-775 -800);
DISPLAY 0.978723 (-775 -800);
PAINT WHITE (-775 -800);
DISPLAY INVISIBLE (-775 -800);
FORCEPROP 2 LAST CDS_LOCATION R25W116
R 1
J 0
(-725 -805);
DISPLAY 0.617021 (-725 -805);
PAINT AQUA (-725 -805);
DISPLAY INVISIBLE (-725 -805);
FORCEADD RES..1
(-600 -1900);
FORCEPROP 1 LAST PART_NUMBER G21796-072
J 0
(-450 -1900);
DISPLAY 0.617021 (-450 -1900);
PAINT BLUE (-450 -1900);
FORCEPROP 1 LAST TOLERANCE 1%
J 0
(-525 -1850);
DISPLAY 0.617021 (-525 -1850);
PAINT SKYBLUE (-525 -1850);
FORCEPROP 1 LASTPIN (-500 -1900) $PN 2
J 0
(-538 -1888);
DISPLAY 0.787234 (-538 -1888);
PAINT ORANGE (-538 -1888);
FORCEPROP 1 LASTPIN (-700 -1900) $PN 1
J 0
(-688 -1888);
DISPLAY 0.787234 (-688 -1888);
PAINT ORANGE (-688 -1888);
FORCEPROP 1 LAST PACK_TYPE 0402
J 0
(-200 -1900);
DISPLAY 0.617021 (-200 -1900);
PAINT SKYBLUE (-200 -1900);
FORCEPROP 1 LAST MATERIAL CHIP
J 0
(-850 -1900);
DISPLAY 0.617021 (-850 -1900);
PAINT SKYBLUE (-850 -1900);
FORCEPROP 1 LAST WATTAGE 1/16W
J 2
(-325 -1850);
DISPLAY 0.617021 (-325 -1850);
PAINT SKYBLUE (-325 -1850);
FORCEPROP 1 LAST VALUE 4.75K
J 2
(-550 -1850);
DISPLAY 0.617021 (-550 -1850);
PAINT SKYBLUE (-550 -1850);
FORCEPROP 1 LAST LOCATION R25W107
J 0
(-850 -1850);
DISPLAY 0.617021 (-850 -1850);
PAINT AQUA (-850 -1850);
FORCEPROP 1 LAST PATH I190
J 0
(-650 -1750);
DISPLAY 0.978723 (-650 -1750);
PAINT WHITE (-650 -1750);
DISPLAY INVISIBLE (-650 -1750);
FORCEPROP 0 LAST CDS_SEC 1
J 0
(-325 -1800);
PAINT MONO (-325 -1800);
DISPLAY INVISIBLE (-325 -1800);
FORCEPROP 2 LAST SEC_TYPE 0402
J 0
(-650 -1700);
DISPLAY 1.021277 (-650 -1700);
PAINT ORANGE (-650 -1700);
DISPLAY INVISIBLE (-650 -1700);
FORCEPROP 0 LAST SEC 1
J 0
(-650 -1800);
PAINT MONO (-650 -1800);
DISPLAY INVISIBLE (-650 -1800);
FORCEPROP 2 LAST ROOM BMC
J 0
(-650 -1800);
DISPLAY 1.021277 (-650 -1800);
PAINT ORANGE (-650 -1800);
DISPLAY INVISIBLE (-650 -1800);
FORCEPROP 2 LAST BOM_COST SM_CONTROLLER
J 0
(-650 -1750);
DISPLAY 1.021277 (-650 -1750);
PAINT ORANGE (-650 -1750);
DISPLAY INVISIBLE (-650 -1750);
FORCEPROP 2 LAST CDS_LIB mstr_discrete
J 0
(-600 -1900);
PAINT MONO (-600 -1900);
DISPLAY INVISIBLE (-600 -1900);
FORCEPROP 0 LAST CDS_LOCATION R25W107
J 0
(-650 -1800);
PAINT MONO (-650 -1800);
DISPLAY INVISIBLE (-650 -1800);
FORCEADD RES..1
(-600 -2100);
FORCEPROP 1 LAST PACK_TYPE 0402
J 0
(-200 -2100);
DISPLAY 0.617021 (-200 -2100);
PAINT SKYBLUE (-200 -2100);
FORCEPROP 1 LAST LOCATION R25W108
J 0
(-850 -2050);
DISPLAY 0.617021 (-850 -2050);
PAINT AQUA (-850 -2050);
FORCEPROP 1 LAST WATTAGE 1/16W
J 2
(-325 -2050);
DISPLAY 0.617021 (-325 -2050);
PAINT SKYBLUE (-325 -2050);
FORCEPROP 1 LAST PART_NUMBER G21796-072
J 0
(-450 -2100);
DISPLAY 0.617021 (-450 -2100);
PAINT BLUE (-450 -2100);
FORCEPROP 1 LAST TOLERANCE 1%
J 0
(-525 -2050);
DISPLAY 0.617021 (-525 -2050);
PAINT SKYBLUE (-525 -2050);
FORCEPROP 1 LASTPIN (-500 -2100) $PN 2
J 0
(-538 -2088);
DISPLAY 0.787234 (-538 -2088);
PAINT ORANGE (-538 -2088);
FORCEPROP 1 LAST VALUE 4.75K
J 2
(-550 -2050);
DISPLAY 0.617021 (-550 -2050);
PAINT SKYBLUE (-550 -2050);
FORCEPROP 1 LASTPIN (-700 -2100) $PN 1
J 0
(-688 -2088);
DISPLAY 0.787234 (-688 -2088);
PAINT ORANGE (-688 -2088);
FORCEPROP 1 LAST MATERIAL EMPTY
J 0
(-850 -2100);
DISPLAY 0.617021 (-850 -2100);
PAINT RED (-850 -2100);
FORCEPROP 2 LAST CDS_LOCATION R25W108
J 0
(-650 -2050);
DISPLAY 0.617021 (-650 -2050);
PAINT AQUA (-650 -2050);
DISPLAY INVISIBLE (-650 -2050);
FORCEPROP 0 LAST CDS_SEC 1
J 0
(-325 -2000);
PAINT MONO (-325 -2000);
DISPLAY INVISIBLE (-325 -2000);
FORCEPROP 2 LAST BOM_COST SM_CONTROLLER
J 0
(-650 -1950);
DISPLAY 1.021277 (-650 -1950);
PAINT ORANGE (-650 -1950);
DISPLAY INVISIBLE (-650 -1950);
FORCEPROP 2 LAST ROOM BMC
J 0
(-650 -2000);
DISPLAY 1.021277 (-650 -2000);
PAINT ORANGE (-650 -2000);
DISPLAY INVISIBLE (-650 -2000);
FORCEPROP 2 LAST CDS_LIB mstr_discrete
J 0
(-600 -2100);
PAINT ORANGE (-600 -2100);
DISPLAY INVISIBLE (-600 -2100);
FORCEPROP 2 LAST SEC 1
J 0
(-650 -1900);
PAINT MONO (-650 -1900);
DISPLAY INVISIBLE (-650 -1900);
FORCEPROP 2 LAST SEC_TYPE 0402
J 0
(-650 -1900);
DISPLAY 1.021277 (-650 -1900);
PAINT ORANGE (-650 -1900);
DISPLAY INVISIBLE (-650 -1900);
FORCEPROP 1 LAST PATH I191
J 0
(-650 -1950);
DISPLAY 0.978723 (-650 -1950);
PAINT WHITE (-650 -1950);
DISPLAY INVISIBLE (-650 -1950);
FORCEADD RES..1
(-600 -400);
FORCEPROP 1 LAST TOLERANCE 1%
J 0
(-525 -350);
DISPLAY 0.617021 (-525 -350);
PAINT SKYBLUE (-525 -350);
FORCEPROP 1 LASTPIN (-500 -400) $PN 2
J 0
(-538 -388);
DISPLAY 0.787234 (-538 -388);
PAINT ORANGE (-538 -388);
FORCEPROP 1 LAST VALUE 4.75K
J 2
(-550 -350);
DISPLAY 0.617021 (-550 -350);
PAINT SKYBLUE (-550 -350);
FORCEPROP 1 LAST LOCATION R25W105
J 0
(-850 -350);
DISPLAY 0.617021 (-850 -350);
PAINT AQUA (-850 -350);
FORCEPROP 1 LASTPIN (-700 -400) $PN 1
J 0
(-688 -388);
DISPLAY 0.787234 (-688 -388);
PAINT ORANGE (-688 -388);
FORCEPROP 1 LAST PACK_TYPE 0402
J 0
(-200 -400);
DISPLAY 0.617021 (-200 -400);
PAINT SKYBLUE (-200 -400);
FORCEPROP 1 LAST WATTAGE 1/16W
J 2
(-325 -350);
DISPLAY 0.617021 (-325 -350);
PAINT SKYBLUE (-325 -350);
FORCEPROP 1 LAST PART_NUMBER G21796-072
J 0
(-450 -400);
DISPLAY 0.617021 (-450 -400);
PAINT BLUE (-450 -400);
FORCEPROP 1 LAST MATERIAL EMPTY
J 0
(-850 -400);
DISPLAY 0.617021 (-850 -400);
PAINT RED (-850 -400);
FORCEPROP 1 LAST PATH I196
J 0
(-650 -250);
DISPLAY 0.978723 (-650 -250);
PAINT WHITE (-650 -250);
DISPLAY INVISIBLE (-650 -250);
FORCEPROP 2 LAST BOM_COST SM_CONTROLLER
J 0
(-650 -250);
DISPLAY 1.021277 (-650 -250);
PAINT ORANGE (-650 -250);
DISPLAY INVISIBLE (-650 -250);
FORCEPROP 2 LAST ROOM BMC
J 0
(-650 -300);
DISPLAY 1.021277 (-650 -300);
PAINT ORANGE (-650 -300);
DISPLAY INVISIBLE (-650 -300);
FORCEPROP 2 LAST CDS_LIB mstr_discrete
J 0
(-600 -400);
PAINT ORANGE (-600 -400);
DISPLAY INVISIBLE (-600 -400);
FORCEPROP 2 LAST CDS_LOCATION R25W105
J 0
(-650 -350);
DISPLAY 0.617021 (-650 -350);
PAINT AQUA (-650 -350);
DISPLAY INVISIBLE (-650 -350);
FORCEPROP 2 LAST SEC 1
J 0
(-650 -200);
PAINT MONO (-650 -200);
DISPLAY INVISIBLE (-650 -200);
FORCEPROP 2 LAST SEC_TYPE 0402
J 0
(-650 -200);
DISPLAY 1.021277 (-650 -200);
PAINT ORANGE (-650 -200);
DISPLAY INVISIBLE (-650 -200);
FORCEADD GND..1
(-900 -1400);
FORCEPROP 3 LASTPIN (-900 -1350) SIG_NAME GND\g
J 0
(-890 -1340);
DISPLAY 0.659574 (-890 -1340);
PAINT MONO (-890 -1340);
DISPLAY INVISIBLE (-890 -1340);
FORCEPROP 2 LAST CDS_LIB mstr_symbols
J 0
(-900 -1400);
PAINT MONO (-900 -1400);
DISPLAY INVISIBLE (-900 -1400);
FORCEPROP 1 LAST SIZE 1B
J 0
(-825 -1450);
DISPLAY 0.872340 (-825 -1450);
PAINT AQUA (-825 -1450);
DISPLAY INVISIBLE (-825 -1450);
FORCEPROP 1 LAST VOLTAGE 0.0V
J 0
(-945 -1443);
DISPLAY 0.340426 (-945 -1443);
PAINT GREEN (-945 -1443);
DISPLAY INVISIBLE (-945 -1443);
FORCEPROP 1 LAST PATH I198
J 0
(-825 -1400);
DISPLAY 0.872340 (-825 -1400);
PAINT AQUA (-825 -1400);
DISPLAY INVISIBLE (-825 -1400);
FORCEPROP 1 LAST BODY_TYPE PLUMBING
J 0
(-945 -1443);
DISPLAY 0.340426 (-945 -1443);
PAINT GREEN (-945 -1443);
DISPLAY INVISIBLE (-945 -1443);
FORCEPROP 1 LAST HDL_POWER GND
J 0
(-900 -1250);
DISPLAY 0.872340 (-900 -1250);
PAINT GREEN (-900 -1250);
DISPLAY INVISIBLE (-900 -1250);
FORCEADD RES..1
(-600 -1300);
FORCEPROP 1 LAST PACK_TYPE 0402
J 0
(-200 -1300);
DISPLAY 0.617021 (-200 -1300);
PAINT SKYBLUE (-200 -1300);
FORCEPROP 1 LAST VALUE 4.75K
J 0
(-650 -1250);
DISPLAY 0.617021 (-650 -1250);
PAINT SKYBLUE (-650 -1250);
FORCEPROP 1 LAST MATERIAL CHIP
J 0
(-850 -1300);
DISPLAY 0.617021 (-850 -1300);
PAINT SKYBLUE (-850 -1300);
FORCEPROP 1 LAST LOCATION R25W146
J 0
(-850 -1250);
DISPLAY 0.617021 (-850 -1250);
PAINT AQUA (-850 -1250);
FORCEPROP 1 LAST PART_NUMBER G21796-072
J 0
(-450 -1300);
DISPLAY 0.617021 (-450 -1300);
PAINT BLUE (-450 -1300);
FORCEPROP 1 LASTPIN (-500 -1300) $PN 2
J 0
(-538 -1288);
DISPLAY 0.787234 (-538 -1288);
PAINT ORANGE (-538 -1288);
FORCEPROP 1 LAST WATTAGE 1/16W
J 0
(-450 -1250);
DISPLAY 0.617021 (-450 -1250);
PAINT SKYBLUE (-450 -1250);
FORCEPROP 1 LASTPIN (-700 -1300) $PN 1
J 0
(-688 -1288);
DISPLAY 0.787234 (-688 -1288);
PAINT ORANGE (-688 -1288);
FORCEPROP 1 LAST TOLERANCE 1%
J 0
(-525 -1250);
DISPLAY 0.617021 (-525 -1250);
PAINT SKYBLUE (-525 -1250);
FORCEPROP 2 LAST BOM_COST SM_CONTROLLER
J 0
(-650 -1150);
DISPLAY 1.021277 (-650 -1150);
PAINT ORANGE (-650 -1150);
DISPLAY INVISIBLE (-650 -1150);
FORCEPROP 2 LAST ROOM BMC
J 0
(-650 -1200);
DISPLAY 1.021277 (-650 -1200);
PAINT ORANGE (-650 -1200);
DISPLAY INVISIBLE (-650 -1200);
FORCEPROP 1 LAST PATH I199
J 0
(-650 -1150);
DISPLAY 0.978723 (-650 -1150);
PAINT WHITE (-650 -1150);
DISPLAY INVISIBLE (-650 -1150);
FORCEPROP 2 LAST CDS_LIB mstr_discrete
J 0
(-600 -1300);
PAINT MONO (-600 -1300);
DISPLAY INVISIBLE (-600 -1300);
FORCEPROP 2 LAST SEC 1
J 0
(-650 -1100);
DISPLAY 0.680851 (-650 -1100);
PAINT MONO (-650 -1100);
DISPLAY INVISIBLE (-650 -1100);
FORCEPROP 2 LAST SEC_TYPE 0402
J 0
(-650 -1100);
DISPLAY 1.021277 (-650 -1100);
PAINT ORANGE (-650 -1100);
DISPLAY INVISIBLE (-650 -1100);
FORCEADD OFFPAGE..2
(3150 -200);
FORCEPROP 2 LAST $XR0 146 
J 0
(3339 -200);
DISPLAY 0.638298 (3339 -200);
PAINT MONO (3339 -200);
FORCEPROP 2 LAST CDS_LIB mstr_standard
J 0
(3150 -200);
PAINT ORANGE (3150 -200);
DISPLAY INVISIBLE (3150 -200);
FORCEPROP 2 LAST PATH I202
J 0
(3350 -150);
DISPLAY 1.021277 (3350 -150);
PAINT ORANGE (3350 -150);
DISPLAY INVISIBLE (3350 -150);
FORCEPROP 1 LAST OFFPAGE TRUE
J 0
(3475 -325);
DISPLAY 0.872340 (3475 -325);
PAINT GREEN (3475 -325);
DISPLAY INVISIBLE (3475 -325);
FORCEPROP 1 LAST COMMENT_BODY TRUE
J 0
(3105 -295);
DISPLAY 0.872340 (3105 -295);
PAINT GREEN (3105 -295);
DISPLAY INVISIBLE (3105 -295);
FORCEADD OFFPAGE..2
(3150 -400);
FORCEPROP 2 LAST $XR0 146 
J 0
(3339 -400);
DISPLAY 0.638298 (3339 -400);
PAINT MONO (3339 -400);
FORCEPROP 2 LAST CDS_LIB mstr_standard
J 0
(3150 -400);
PAINT MONO (3150 -400);
DISPLAY INVISIBLE (3150 -400);
FORCEPROP 2 LAST PATH I203
J 0
(3350 -350);
DISPLAY 1.021277 (3350 -350);
PAINT ORANGE (3350 -350);
DISPLAY INVISIBLE (3350 -350);
FORCEPROP 1 LAST OFFPAGE TRUE
J 0
(3475 -525);
DISPLAY 0.872340 (3475 -525);
PAINT GREEN (3475 -525);
DISPLAY INVISIBLE (3475 -525);
FORCEPROP 1 LAST COMMENT_BODY TRUE
J 0
(3105 -495);
DISPLAY 0.872340 (3105 -495);
PAINT GREEN (3105 -495);
DISPLAY INVISIBLE (3105 -495);
FORCEADD OFFPAGE..2
(3150 -600);
FORCEPROP 2 LAST $XR0 146 
J 0
(3339 -600);
DISPLAY 0.638298 (3339 -600);
PAINT MONO (3339 -600);
FORCEPROP 2 LAST PATH I204
J 0
(3350 -550);
DISPLAY 1.021277 (3350 -550);
PAINT ORANGE (3350 -550);
DISPLAY INVISIBLE (3350 -550);
FORCEPROP 2 LAST CDS_LIB mstr_standard
J 0
(3150 -600);
PAINT ORANGE (3150 -600);
DISPLAY INVISIBLE (3150 -600);
FORCEPROP 1 LAST OFFPAGE TRUE
J 0
(3475 -725);
DISPLAY 0.872340 (3475 -725);
PAINT GREEN (3475 -725);
DISPLAY INVISIBLE (3475 -725);
FORCEPROP 1 LAST COMMENT_BODY TRUE
J 0
(3105 -695);
DISPLAY 0.872340 (3105 -695);
PAINT GREEN (3105 -695);
DISPLAY INVISIBLE (3105 -695);
FORCEADD OFFPAGE..2
(3150 -800);
FORCEPROP 2 LAST $XR0 146 
J 0
(3339 -800);
DISPLAY 0.638298 (3339 -800);
PAINT MONO (3339 -800);
FORCEPROP 2 LAST CDS_LIB mstr_standard
J 0
(3150 -800);
PAINT MONO (3150 -800);
DISPLAY INVISIBLE (3150 -800);
FORCEPROP 2 LAST PATH I205
J 0
(3350 -750);
DISPLAY 1.021277 (3350 -750);
PAINT ORANGE (3350 -750);
DISPLAY INVISIBLE (3350 -750);
FORCEPROP 1 LAST OFFPAGE TRUE
J 0
(3475 -925);
DISPLAY 0.872340 (3475 -925);
PAINT GREEN (3475 -925);
DISPLAY INVISIBLE (3475 -925);
FORCEPROP 1 LAST COMMENT_BODY TRUE
J 0
(3105 -895);
DISPLAY 0.872340 (3105 -895);
PAINT GREEN (3105 -895);
DISPLAY INVISIBLE (3105 -895);
FORCEADD OFFPAGE..2
(3150 -1000);
FORCEPROP 2 LAST $XR0 146 
J 0
(3339 -1000);
DISPLAY 0.638298 (3339 -1000);
PAINT MONO (3339 -1000);
FORCEPROP 2 LAST CDS_LIB mstr_standard
J 0
(3150 -1000);
PAINT ORANGE (3150 -1000);
DISPLAY INVISIBLE (3150 -1000);
FORCEPROP 2 LAST PATH I206
J 0
(3350 -950);
DISPLAY 1.021277 (3350 -950);
PAINT ORANGE (3350 -950);
DISPLAY INVISIBLE (3350 -950);
FORCEPROP 1 LAST OFFPAGE TRUE
J 0
(3475 -1125);
DISPLAY 0.872340 (3475 -1125);
PAINT GREEN (3475 -1125);
DISPLAY INVISIBLE (3475 -1125);
FORCEPROP 1 LAST COMMENT_BODY TRUE
J 0
(3105 -1095);
DISPLAY 0.872340 (3105 -1095);
PAINT GREEN (3105 -1095);
DISPLAY INVISIBLE (3105 -1095);
FORCEADD OFFPAGE..2
(3150 -1200);
FORCEPROP 2 LAST $XR0 146 
J 0
(3339 -1200);
DISPLAY 0.638298 (3339 -1200);
PAINT MONO (3339 -1200);
FORCEPROP 2 LAST CDS_LIB mstr_standard
J 0
(3150 -1200);
PAINT MONO (3150 -1200);
DISPLAY INVISIBLE (3150 -1200);
FORCEPROP 2 LAST PATH I207
J 0
(3350 -1150);
DISPLAY 1.021277 (3350 -1150);
PAINT ORANGE (3350 -1150);
DISPLAY INVISIBLE (3350 -1150);
FORCEPROP 1 LAST OFFPAGE TRUE
J 0
(3475 -1325);
DISPLAY 0.872340 (3475 -1325);
PAINT GREEN (3475 -1325);
DISPLAY INVISIBLE (3475 -1325);
FORCEPROP 1 LAST COMMENT_BODY TRUE
J 0
(3105 -1295);
DISPLAY 0.872340 (3105 -1295);
PAINT GREEN (3105 -1295);
DISPLAY INVISIBLE (3105 -1295);
FORCEADD OFFPAGE..2
(3150 -1400);
FORCEPROP 2 LAST $XR0 146 
J 0
(3339 -1400);
DISPLAY 0.638298 (3339 -1400);
PAINT MONO (3339 -1400);
FORCEPROP 2 LAST CDS_LIB mstr_standard
J 0
(3150 -1400);
PAINT MONO (3150 -1400);
DISPLAY INVISIBLE (3150 -1400);
FORCEPROP 2 LAST PATH I208
J 0
(3350 -1350);
DISPLAY 1.021277 (3350 -1350);
PAINT ORANGE (3350 -1350);
DISPLAY INVISIBLE (3350 -1350);
FORCEPROP 1 LAST OFFPAGE TRUE
J 0
(3475 -1525);
DISPLAY 0.872340 (3475 -1525);
PAINT GREEN (3475 -1525);
DISPLAY INVISIBLE (3475 -1525);
FORCEPROP 1 LAST COMMENT_BODY TRUE
J 0
(3105 -1495);
DISPLAY 0.872340 (3105 -1495);
PAINT GREEN (3105 -1495);
DISPLAY INVISIBLE (3105 -1495);
FORCEADD RES..1
(1850 -200);
FORCEPROP 1 LAST VALUE 4.75K
J 2
(1900 -150);
DISPLAY 0.617021 (1900 -150);
PAINT SKYBLUE (1900 -150);
FORCEPROP 1 LAST MATERIAL EMPTY
J 0
(1600 -200);
DISPLAY 0.617021 (1600 -200);
PAINT RED (1600 -200);
FORCEPROP 1 LASTPIN (1950 -200) $PN 2
J 0
(1912 -188);
DISPLAY 0.787234 (1912 -188);
PAINT ORANGE (1912 -188);
FORCEPROP 1 LASTPIN (1750 -200) $PN 1
J 0
(1762 -188);
DISPLAY 0.787234 (1762 -188);
PAINT ORANGE (1762 -188);
FORCEPROP 1 LAST LOCATION R25W98
J 0
(1600 -150);
DISPLAY 0.617021 (1600 -150);
PAINT AQUA (1600 -150);
FORCEPROP 1 LAST WATTAGE 1/16W
J 2
(2125 -150);
DISPLAY 0.617021 (2125 -150);
PAINT SKYBLUE (2125 -150);
FORCEPROP 1 LAST TOLERANCE 1%
J 0
(1925 -150);
DISPLAY 0.617021 (1925 -150);
PAINT SKYBLUE (1925 -150);
FORCEPROP 1 LAST PART_NUMBER G21796-072
J 0
(2000 -200);
DISPLAY 0.617021 (2000 -200);
PAINT BLUE (2000 -200);
FORCEPROP 1 LAST PACK_TYPE 0402
J 0
(2250 -200);
DISPLAY 0.617021 (2250 -200);
PAINT SKYBLUE (2250 -200);
FORCEPROP 1 LAST PATH I209
J 0
(1800 -50);
DISPLAY 0.978723 (1800 -50);
PAINT WHITE (1800 -50);
DISPLAY INVISIBLE (1800 -50);
FORCEPROP 2 LAST BOM_COST SM_CONTROLLER
J 0
(1800 -50);
DISPLAY 1.021277 (1800 -50);
PAINT ORANGE (1800 -50);
DISPLAY INVISIBLE (1800 -50);
FORCEPROP 2 LAST ROOM BMC
J 0
(1800 -100);
DISPLAY 1.021277 (1800 -100);
PAINT ORANGE (1800 -100);
DISPLAY INVISIBLE (1800 -100);
FORCEPROP 2 LAST CDS_LIB mstr_discrete
J 0
(1850 -200);
PAINT MONO (1850 -200);
DISPLAY INVISIBLE (1850 -200);
FORCEPROP 2 LAST SEC 1
J 0
(1800 0);
DISPLAY 0.680851 (1800 0);
PAINT MONO (1800 0);
DISPLAY INVISIBLE (1800 0);
FORCEPROP 2 LAST SEC_TYPE 0402
J 0
(1800 0);
DISPLAY 1.021277 (1800 0);
PAINT ORANGE (1800 0);
DISPLAY INVISIBLE (1800 0);
FORCEADD RES..1
(1850 -400);
FORCEPROP 1 LAST VALUE 4.75K
J 2
(1900 -350);
DISPLAY 0.617021 (1900 -350);
PAINT SKYBLUE (1900 -350);
FORCEPROP 1 LAST PART_NUMBER G21796-072
J 0
(2000 -400);
DISPLAY 0.617021 (2000 -400);
PAINT BLUE (2000 -400);
FORCEPROP 1 LASTPIN (1950 -400) $PN 2
J 0
(1912 -388);
DISPLAY 0.787234 (1912 -388);
PAINT ORANGE (1912 -388);
FORCEPROP 1 LASTPIN (1750 -400) $PN 1
J 0
(1762 -388);
DISPLAY 0.787234 (1762 -388);
PAINT ORANGE (1762 -388);
FORCEPROP 1 LAST MATERIAL EMPTY
J 0
(1600 -400);
DISPLAY 0.617021 (1600 -400);
PAINT RED (1600 -400);
FORCEPROP 1 LAST WATTAGE 1/16W
J 2
(2125 -350);
DISPLAY 0.617021 (2125 -350);
PAINT SKYBLUE (2125 -350);
FORCEPROP 1 LAST TOLERANCE 1%
J 0
(1925 -350);
DISPLAY 0.617021 (1925 -350);
PAINT SKYBLUE (1925 -350);
FORCEPROP 1 LAST PACK_TYPE 0402
J 0
(2250 -400);
DISPLAY 0.617021 (2250 -400);
PAINT SKYBLUE (2250 -400);
FORCEPROP 1 LAST LOCATION R25W99
J 0
(1600 -350);
DISPLAY 0.617021 (1600 -350);
PAINT AQUA (1600 -350);
FORCEPROP 1 LAST PATH I210
J 0
(1800 -250);
DISPLAY 0.978723 (1800 -250);
PAINT WHITE (1800 -250);
DISPLAY INVISIBLE (1800 -250);
FORCEPROP 2 LAST CDS_LIB mstr_discrete
J 0
(1850 -400);
PAINT ORANGE (1850 -400);
DISPLAY INVISIBLE (1850 -400);
FORCEPROP 2 LAST ROOM BMC
J 0
(1800 -300);
DISPLAY 1.021277 (1800 -300);
PAINT ORANGE (1800 -300);
DISPLAY INVISIBLE (1800 -300);
FORCEPROP 2 LAST BOM_COST SM_CONTROLLER
J 0
(1800 -250);
DISPLAY 1.021277 (1800 -250);
PAINT ORANGE (1800 -250);
DISPLAY INVISIBLE (1800 -250);
FORCEPROP 2 LAST CDS_LOCATION R25W99
J 0
(1800 -350);
DISPLAY 0.617021 (1800 -350);
PAINT AQUA (1800 -350);
DISPLAY INVISIBLE (1800 -350);
FORCEPROP 2 LAST SEC 1
J 0
(1800 -200);
PAINT MONO (1800 -200);
DISPLAY INVISIBLE (1800 -200);
FORCEPROP 2 LAST SEC_TYPE 0402
J 0
(1800 -200);
DISPLAY 1.021277 (1800 -200);
PAINT ORANGE (1800 -200);
DISPLAY INVISIBLE (1800 -200);
FORCEADD RES..1
(1850 -600);
FORCEPROP 1 LAST MATERIAL CHIP
J 0
(1600 -600);
DISPLAY 0.617021 (1600 -600);
PAINT SKYBLUE (1600 -600);
FORCEPROP 1 LAST TOLERANCE 1%
J 0
(1925 -550);
DISPLAY 0.617021 (1925 -550);
PAINT SKYBLUE (1925 -550);
FORCEPROP 1 LASTPIN (1950 -600) $PN 2
J 0
(1912 -588);
DISPLAY 0.787234 (1912 -588);
PAINT ORANGE (1912 -588);
FORCEPROP 1 LASTPIN (1750 -600) $PN 1
J 0
(1762 -588);
DISPLAY 0.787234 (1762 -588);
PAINT ORANGE (1762 -588);
FORCEPROP 1 LAST WATTAGE 1/16W
J 2
(2125 -550);
DISPLAY 0.617021 (2125 -550);
PAINT SKYBLUE (2125 -550);
FORCEPROP 1 LAST VALUE 4.75K
J 2
(1900 -550);
DISPLAY 0.617021 (1900 -550);
PAINT SKYBLUE (1900 -550);
FORCEPROP 1 LAST LOCATION R25W100
J 0
(1600 -550);
DISPLAY 0.617021 (1600 -550);
PAINT AQUA (1600 -550);
FORCEPROP 1 LAST PACK_TYPE 0402
J 0
(2250 -600);
DISPLAY 0.617021 (2250 -600);
PAINT SKYBLUE (2250 -600);
FORCEPROP 1 LAST PART_NUMBER G21796-072
J 0
(2000 -600);
DISPLAY 0.617021 (2000 -600);
PAINT BLUE (2000 -600);
FORCEPROP 0 LAST CDS_LOCATION R25W100
J 0
(1800 -500);
PAINT MONO (1800 -500);
DISPLAY INVISIBLE (1800 -500);
FORCEPROP 2 LAST ROOM BMC
J 0
(1800 -500);
DISPLAY 1.021277 (1800 -500);
PAINT ORANGE (1800 -500);
DISPLAY INVISIBLE (1800 -500);
FORCEPROP 2 LAST BOM_COST SM_CONTROLLER
J 0
(1800 -450);
DISPLAY 1.021277 (1800 -450);
PAINT ORANGE (1800 -450);
DISPLAY INVISIBLE (1800 -450);
FORCEPROP 2 LAST CDS_LIB mstr_discrete
J 0
(1850 -600);
PAINT MONO (1850 -600);
DISPLAY INVISIBLE (1850 -600);
FORCEPROP 0 LAST SEC 1
J 0
(1800 -500);
PAINT MONO (1800 -500);
DISPLAY INVISIBLE (1800 -500);
FORCEPROP 2 LAST SEC_TYPE 0402
J 0
(1800 -400);
DISPLAY 1.021277 (1800 -400);
PAINT ORANGE (1800 -400);
DISPLAY INVISIBLE (1800 -400);
FORCEPROP 0 LAST CDS_SEC 1
J 0
(2125 -500);
PAINT MONO (2125 -500);
DISPLAY INVISIBLE (2125 -500);
FORCEPROP 1 LAST PATH I211
J 0
(1800 -450);
DISPLAY 0.978723 (1800 -450);
PAINT WHITE (1800 -450);
DISPLAY INVISIBLE (1800 -450);
FORCEADD RES..1
(1850 -1200);
FORCEPROP 1 LAST PART_NUMBER G21796-072
J 0
(2000 -1200);
DISPLAY 0.617021 (2000 -1200);
PAINT BLUE (2000 -1200);
FORCEPROP 1 LAST WATTAGE 1/16W
J 2
(2125 -1150);
DISPLAY 0.617021 (2125 -1150);
PAINT SKYBLUE (2125 -1150);
FORCEPROP 1 LASTPIN (1750 -1200) $PN 1
J 0
(1762 -1188);
DISPLAY 0.787234 (1762 -1188);
PAINT ORANGE (1762 -1188);
FORCEPROP 1 LAST PACK_TYPE 0402
J 0
(2250 -1200);
DISPLAY 0.617021 (2250 -1200);
PAINT SKYBLUE (2250 -1200);
FORCEPROP 1 LAST MATERIAL EMPTY
J 0
(1600 -1200);
DISPLAY 0.617021 (1600 -1200);
PAINT RED (1600 -1200);
FORCEPROP 1 LAST TOLERANCE 1%
J 0
(1925 -1150);
DISPLAY 0.617021 (1925 -1150);
PAINT SKYBLUE (1925 -1150);
FORCEPROP 1 LAST LOCATION R25W103
J 0
(1600 -1150);
DISPLAY 0.617021 (1600 -1150);
PAINT AQUA (1600 -1150);
FORCEPROP 1 LAST VALUE 4.75K
J 2
(1900 -1150);
DISPLAY 0.617021 (1900 -1150);
PAINT SKYBLUE (1900 -1150);
FORCEPROP 1 LASTPIN (1950 -1200) $PN 2
J 0
(1912 -1188);
DISPLAY 0.787234 (1912 -1188);
PAINT ORANGE (1912 -1188);
FORCEPROP 1 LAST PATH I214
J 0
(1800 -1050);
DISPLAY 0.978723 (1800 -1050);
PAINT WHITE (1800 -1050);
DISPLAY INVISIBLE (1800 -1050);
FORCEPROP 0 LAST CDS_SEC 1
J 0
(2125 -1100);
PAINT MONO (2125 -1100);
DISPLAY INVISIBLE (2125 -1100);
FORCEPROP 2 LAST SEC_TYPE 0402
J 0
(1800 -1000);
DISPLAY 1.021277 (1800 -1000);
PAINT ORANGE (1800 -1000);
DISPLAY INVISIBLE (1800 -1000);
FORCEPROP 2 LAST SEC 1
J 0
(1800 -1000);
PAINT MONO (1800 -1000);
DISPLAY INVISIBLE (1800 -1000);
FORCEPROP 2 LAST CDS_LIB mstr_discrete
J 0
(1850 -1200);
PAINT ORANGE (1850 -1200);
DISPLAY INVISIBLE (1850 -1200);
FORCEPROP 2 LAST CDS_LOCATION R25W103
J 0
(1800 -1150);
DISPLAY 0.617021 (1800 -1150);
PAINT AQUA (1800 -1150);
DISPLAY INVISIBLE (1800 -1150);
FORCEPROP 2 LAST ROOM BMC
J 0
(1800 -1100);
DISPLAY 1.021277 (1800 -1100);
PAINT ORANGE (1800 -1100);
DISPLAY INVISIBLE (1800 -1100);
FORCEPROP 2 LAST BOM_COST SM_CONTROLLER
J 0
(1800 -1050);
DISPLAY 1.021277 (1800 -1050);
PAINT ORANGE (1800 -1050);
DISPLAY INVISIBLE (1800 -1050);
FORCEADD RES..1
(1850 -1400);
FORCEPROP 1 LAST PACK_TYPE 0402
J 0
(2250 -1400);
DISPLAY 0.617021 (2250 -1400);
PAINT SKYBLUE (2250 -1400);
FORCEPROP 1 LAST PART_NUMBER G21796-072
J 0
(2000 -1400);
DISPLAY 0.617021 (2000 -1400);
PAINT BLUE (2000 -1400);
FORCEPROP 1 LAST WATTAGE 1/16W
J 2
(2125 -1350);
DISPLAY 0.617021 (2125 -1350);
PAINT SKYBLUE (2125 -1350);
FORCEPROP 1 LAST TOLERANCE 1%
J 0
(1925 -1350);
DISPLAY 0.617021 (1925 -1350);
PAINT SKYBLUE (1925 -1350);
FORCEPROP 1 LAST MATERIAL CHIP
J 0
(1600 -1400);
DISPLAY 0.617021 (1600 -1400);
PAINT SKYBLUE (1600 -1400);
FORCEPROP 1 LASTPIN (1750 -1400) $PN 1
J 0
(1762 -1388);
DISPLAY 0.787234 (1762 -1388);
PAINT ORANGE (1762 -1388);
FORCEPROP 1 LAST LOCATION R25W104
J 0
(1600 -1350);
DISPLAY 0.617021 (1600 -1350);
PAINT AQUA (1600 -1350);
FORCEPROP 1 LAST VALUE 4.75K
J 2
(1900 -1350);
DISPLAY 0.617021 (1900 -1350);
PAINT SKYBLUE (1900 -1350);
FORCEPROP 1 LASTPIN (1950 -1400) $PN 2
J 0
(1912 -1388);
DISPLAY 0.787234 (1912 -1388);
PAINT ORANGE (1912 -1388);
FORCEPROP 1 LAST PATH I215
J 0
(1800 -1250);
DISPLAY 0.978723 (1800 -1250);
PAINT WHITE (1800 -1250);
DISPLAY INVISIBLE (1800 -1250);
FORCEPROP 0 LAST CDS_SEC 1
J 0
(2125 -1300);
PAINT MONO (2125 -1300);
DISPLAY INVISIBLE (2125 -1300);
FORCEPROP 2 LAST SEC_TYPE 0402
J 0
(1800 -1200);
DISPLAY 1.021277 (1800 -1200);
PAINT ORANGE (1800 -1200);
DISPLAY INVISIBLE (1800 -1200);
FORCEPROP 0 LAST SEC 1
J 0
(1800 -1300);
PAINT MONO (1800 -1300);
DISPLAY INVISIBLE (1800 -1300);
FORCEPROP 2 LAST ROOM BMC
J 0
(1800 -1300);
DISPLAY 1.021277 (1800 -1300);
PAINT ORANGE (1800 -1300);
DISPLAY INVISIBLE (1800 -1300);
FORCEPROP 2 LAST BOM_COST SM_CONTROLLER
J 0
(1800 -1250);
DISPLAY 1.021277 (1800 -1250);
PAINT ORANGE (1800 -1250);
DISPLAY INVISIBLE (1800 -1250);
FORCEPROP 2 LAST CDS_LIB mstr_discrete
J 0
(1850 -1400);
PAINT MONO (1850 -1400);
DISPLAY INVISIBLE (1850 -1400);
FORCEPROP 0 LAST CDS_LOCATION R25W104
J 0
(1800 -1300);
PAINT MONO (1800 -1300);
DISPLAY INVISIBLE (1800 -1300);
FORCEADD RES..1
(-600 -2300);
FORCEPROP 1 LAST WATTAGE 1/16W
J 0
(-450 -2250);
DISPLAY 0.617021 (-450 -2250);
PAINT SKYBLUE (-450 -2250);
FORCEPROP 1 LAST VALUE 4.75K
J 0
(-650 -2250);
DISPLAY 0.617021 (-650 -2250);
PAINT SKYBLUE (-650 -2250);
FORCEPROP 1 LAST PACK_TYPE 0402
J 0
(-200 -2300);
DISPLAY 0.617021 (-200 -2300);
PAINT SKYBLUE (-200 -2300);
FORCEPROP 1 LAST MATERIAL CHIP
J 0
(-850 -2300);
DISPLAY 0.617021 (-850 -2300);
PAINT SKYBLUE (-850 -2300);
FORCEPROP 1 LASTPIN (-700 -2300) $PN 1
J 0
(-688 -2288);
DISPLAY 0.787234 (-688 -2288);
PAINT ORANGE (-688 -2288);
FORCEPROP 1 LASTPIN (-500 -2300) $PN 2
J 0
(-538 -2288);
DISPLAY 0.787234 (-538 -2288);
PAINT ORANGE (-538 -2288);
FORCEPROP 1 LAST LOCATION R25W148
J 0
(-850 -2250);
DISPLAY 0.617021 (-850 -2250);
PAINT AQUA (-850 -2250);
FORCEPROP 1 LAST PART_NUMBER G21796-072
J 0
(-450 -2300);
DISPLAY 0.617021 (-450 -2300);
PAINT BLUE (-450 -2300);
FORCEPROP 1 LAST TOLERANCE 1%
J 0
(-525 -2250);
DISPLAY 0.617021 (-525 -2250);
PAINT SKYBLUE (-525 -2250);
FORCEPROP 2 LAST SEC_TYPE 0402
J 0
(-650 -2100);
DISPLAY 1.021277 (-650 -2100);
PAINT ORANGE (-650 -2100);
DISPLAY INVISIBLE (-650 -2100);
FORCEPROP 2 LAST SEC 1
J 0
(-650 -2100);
DISPLAY 0.680851 (-650 -2100);
PAINT MONO (-650 -2100);
DISPLAY INVISIBLE (-650 -2100);
FORCEPROP 1 LAST PATH I216
J 0
(-650 -2150);
DISPLAY 0.978723 (-650 -2150);
PAINT WHITE (-650 -2150);
DISPLAY INVISIBLE (-650 -2150);
FORCEPROP 2 LAST CDS_LIB mstr_discrete
J 0
(-600 -2300);
PAINT MONO (-600 -2300);
DISPLAY INVISIBLE (-600 -2300);
FORCEPROP 2 LAST ROOM BMC
J 0
(-650 -2200);
DISPLAY 1.021277 (-650 -2200);
PAINT ORANGE (-650 -2200);
DISPLAY INVISIBLE (-650 -2200);
FORCEPROP 2 LAST BOM_COST SM_CONTROLLER
J 0
(-650 -2150);
DISPLAY 1.021277 (-650 -2150);
PAINT ORANGE (-650 -2150);
DISPLAY INVISIBLE (-650 -2150);
FORCEADD GND..1
(-900 -2400);
FORCEPROP 3 LASTPIN (-900 -2350) SIG_NAME GND\g
J 0
(-890 -2340);
DISPLAY 0.659574 (-890 -2340);
PAINT MONO (-890 -2340);
DISPLAY INVISIBLE (-890 -2340);
FORCEPROP 1 LAST PATH I217
J 0
(-825 -2400);
DISPLAY 0.872340 (-825 -2400);
PAINT AQUA (-825 -2400);
DISPLAY INVISIBLE (-825 -2400);
FORCEPROP 1 LAST VOLTAGE 0.0V
J 0
(-945 -2443);
DISPLAY 0.340426 (-945 -2443);
PAINT GREEN (-945 -2443);
DISPLAY INVISIBLE (-945 -2443);
FORCEPROP 1 LAST SIZE 1B
J 0
(-825 -2450);
DISPLAY 0.872340 (-825 -2450);
PAINT AQUA (-825 -2450);
DISPLAY INVISIBLE (-825 -2450);
FORCEPROP 2 LAST CDS_LIB mstr_symbols
J 0
(-900 -2400);
PAINT MONO (-900 -2400);
DISPLAY INVISIBLE (-900 -2400);
FORCEPROP 1 LAST BODY_TYPE PLUMBING
J 0
(-945 -2443);
DISPLAY 0.340426 (-945 -2443);
PAINT GREEN (-945 -2443);
DISPLAY INVISIBLE (-945 -2443);
FORCEPROP 1 LAST HDL_POWER GND
J 0
(-900 -2250);
DISPLAY 0.872340 (-900 -2250);
PAINT GREEN (-900 -2250);
DISPLAY INVISIBLE (-900 -2250);
FORCEADD RES..1
(-600 -2500);
FORCEPROP 1 LAST PART_NUMBER G21796-072
J 0
(-450 -2500);
DISPLAY 0.617021 (-450 -2500);
PAINT BLUE (-450 -2500);
FORCEPROP 1 LAST WATTAGE 1/16W
J 2
(-325 -2450);
DISPLAY 0.617021 (-325 -2450);
PAINT SKYBLUE (-325 -2450);
FORCEPROP 1 LASTPIN (-500 -2500) $PN 2
J 0
(-538 -2488);
DISPLAY 0.787234 (-538 -2488);
PAINT ORANGE (-538 -2488);
FORCEPROP 1 LAST TOLERANCE 1%
J 0
(-525 -2450);
DISPLAY 0.617021 (-525 -2450);
PAINT SKYBLUE (-525 -2450);
FORCEPROP 1 LAST VALUE 4.75K
J 2
(-550 -2450);
DISPLAY 0.617021 (-550 -2450);
PAINT SKYBLUE (-550 -2450);
FORCEPROP 1 LASTPIN (-700 -2500) $PN 1
J 0
(-688 -2488);
DISPLAY 0.787234 (-688 -2488);
PAINT ORANGE (-688 -2488);
FORCEPROP 1 LAST MATERIAL EMPTY
J 0
(-850 -2500);
DISPLAY 0.617021 (-850 -2500);
PAINT RED (-850 -2500);
FORCEPROP 1 LAST LOCATION R25W114
J 0
(-850 -2450);
DISPLAY 0.617021 (-850 -2450);
PAINT AQUA (-850 -2450);
FORCEPROP 1 LAST PACK_TYPE 0402
J 0
(-200 -2500);
DISPLAY 0.617021 (-200 -2500);
PAINT SKYBLUE (-200 -2500);
FORCEPROP 1 LAST PATH I218
J 0
(-650 -2350);
DISPLAY 0.978723 (-650 -2350);
PAINT WHITE (-650 -2350);
DISPLAY INVISIBLE (-650 -2350);
FORCEPROP 0 LAST CDS_SEC 1
J 0
(-325 -2400);
PAINT MONO (-325 -2400);
DISPLAY INVISIBLE (-325 -2400);
FORCEPROP 2 LAST SEC_TYPE 0402
J 0
(-650 -2300);
DISPLAY 1.021277 (-650 -2300);
PAINT ORANGE (-650 -2300);
DISPLAY INVISIBLE (-650 -2300);
FORCEPROP 2 LAST SEC 1
J 0
(-650 -2300);
PAINT MONO (-650 -2300);
DISPLAY INVISIBLE (-650 -2300);
FORCEPROP 2 LAST CDS_LOCATION R25W114
J 0
(-650 -2450);
DISPLAY 0.617021 (-650 -2450);
PAINT AQUA (-650 -2450);
DISPLAY INVISIBLE (-650 -2450);
FORCEPROP 2 LAST CDS_LIB mstr_discrete
J 0
(-600 -2500);
PAINT ORANGE (-600 -2500);
DISPLAY INVISIBLE (-600 -2500);
FORCEPROP 2 LAST ROOM BMC
J 0
(-650 -2400);
DISPLAY 1.021277 (-650 -2400);
PAINT ORANGE (-650 -2400);
DISPLAY INVISIBLE (-650 -2400);
FORCEPROP 2 LAST BOM_COST SM_CONTROLLER
J 0
(-650 -2350);
DISPLAY 1.021277 (-650 -2350);
PAINT ORANGE (-650 -2350);
DISPLAY INVISIBLE (-650 -2350);
FORCEADD RES..1
(-600 -2700);
FORCEPROP 1 LAST PART_NUMBER G21796-072
J 0
(-450 -2700);
DISPLAY 0.617021 (-450 -2700);
PAINT BLUE (-450 -2700);
FORCEPROP 1 LAST MATERIAL CHIP
J 0
(-850 -2700);
DISPLAY 0.617021 (-850 -2700);
PAINT SKYBLUE (-850 -2700);
FORCEPROP 1 LAST PACK_TYPE 0402
J 0
(-200 -2700);
DISPLAY 0.617021 (-200 -2700);
PAINT SKYBLUE (-200 -2700);
FORCEPROP 1 LAST WATTAGE 1/16W
J 0
(-450 -2650);
DISPLAY 0.617021 (-450 -2650);
PAINT SKYBLUE (-450 -2650);
FORCEPROP 1 LASTPIN (-500 -2700) $PN 2
J 0
(-538 -2688);
DISPLAY 0.787234 (-538 -2688);
PAINT ORANGE (-538 -2688);
FORCEPROP 1 LAST VALUE 4.75K
J 0
(-650 -2650);
DISPLAY 0.617021 (-650 -2650);
PAINT SKYBLUE (-650 -2650);
FORCEPROP 1 LAST TOLERANCE 1%
J 0
(-525 -2650);
DISPLAY 0.617021 (-525 -2650);
PAINT SKYBLUE (-525 -2650);
FORCEPROP 1 LASTPIN (-700 -2700) $PN 1
J 0
(-688 -2688);
DISPLAY 0.787234 (-688 -2688);
PAINT ORANGE (-688 -2688);
FORCEPROP 1 LAST LOCATION R25W149
J 0
(-850 -2650);
DISPLAY 0.617021 (-850 -2650);
PAINT AQUA (-850 -2650);
FORCEPROP 2 LAST SEC 1
J 0
(-650 -2500);
DISPLAY 0.680851 (-650 -2500);
PAINT MONO (-650 -2500);
DISPLAY INVISIBLE (-650 -2500);
FORCEPROP 2 LAST SEC_TYPE 0402
J 0
(-650 -2500);
DISPLAY 1.021277 (-650 -2500);
PAINT ORANGE (-650 -2500);
DISPLAY INVISIBLE (-650 -2500);
FORCEPROP 2 LAST BOM_COST SM_CONTROLLER
J 0
(-650 -2550);
DISPLAY 1.021277 (-650 -2550);
PAINT ORANGE (-650 -2550);
DISPLAY INVISIBLE (-650 -2550);
FORCEPROP 2 LAST ROOM BMC
J 0
(-650 -2600);
DISPLAY 1.021277 (-650 -2600);
PAINT ORANGE (-650 -2600);
DISPLAY INVISIBLE (-650 -2600);
FORCEPROP 2 LAST CDS_LIB mstr_discrete
J 0
(-600 -2700);
PAINT MONO (-600 -2700);
DISPLAY INVISIBLE (-600 -2700);
FORCEPROP 1 LAST PATH I219
J 0
(-650 -2550);
DISPLAY 0.978723 (-650 -2550);
PAINT WHITE (-650 -2550);
DISPLAY INVISIBLE (-650 -2550);
FORCEADD OFFPAGE..2
(850 -2500);
FORCEPROP 2 LAST $XR0 147 
J 0
(1039 -2500);
DISPLAY 0.638298 (1039 -2500);
PAINT MONO (1039 -2500);
FORCEPROP 2 LAST PATH I220
J 0
(1050 -2450);
DISPLAY 1.021277 (1050 -2450);
PAINT ORANGE (1050 -2450);
DISPLAY INVISIBLE (1050 -2450);
FORCEPROP 2 LAST CDS_LIB mstr_standard
J 0
(850 -2500);
PAINT MONO (850 -2500);
DISPLAY INVISIBLE (850 -2500);
FORCEPROP 1 LAST OFFPAGE TRUE
J 0
(1175 -2625);
DISPLAY 0.872340 (1175 -2625);
PAINT GREEN (1175 -2625);
DISPLAY INVISIBLE (1175 -2625);
FORCEPROP 1 LAST COMMENT_BODY TRUE
J 0
(805 -2595);
DISPLAY 0.872340 (805 -2595);
PAINT GREEN (805 -2595);
DISPLAY INVISIBLE (805 -2595);
FORCEADD OFFPAGE..2
(850 -2900);
FORCEPROP 2 LAST $XR0 147 
J 0
(1039 -2900);
DISPLAY 0.638298 (1039 -2900);
PAINT MONO (1039 -2900);
FORCEPROP 2 LAST PATH I221
J 0
(1050 -2850);
DISPLAY 1.021277 (1050 -2850);
PAINT ORANGE (1050 -2850);
DISPLAY INVISIBLE (1050 -2850);
FORCEPROP 2 LAST CDS_LIB mstr_standard
J 0
(850 -2900);
PAINT ORANGE (850 -2900);
DISPLAY INVISIBLE (850 -2900);
FORCEPROP 1 LAST OFFPAGE TRUE
J 0
(1175 -3025);
DISPLAY 0.872340 (1175 -3025);
PAINT GREEN (1175 -3025);
DISPLAY INVISIBLE (1175 -3025);
FORCEPROP 1 LAST COMMENT_BODY TRUE
J 0
(805 -2995);
DISPLAY 0.872340 (805 -2995);
PAINT GREEN (805 -2995);
DISPLAY INVISIBLE (805 -2995);
FORCEADD OFFPAGE..2
(850 -3100);
FORCEPROP 2 LAST $XR0 147 
J 0
(1039 -3100);
DISPLAY 0.638298 (1039 -3100);
PAINT MONO (1039 -3100);
FORCEPROP 2 LAST PATH I222
J 0
(1050 -3050);
DISPLAY 1.021277 (1050 -3050);
PAINT ORANGE (1050 -3050);
DISPLAY INVISIBLE (1050 -3050);
FORCEPROP 2 LAST CDS_LIB mstr_standard
J 0
(850 -3100);
PAINT MONO (850 -3100);
DISPLAY INVISIBLE (850 -3100);
FORCEPROP 1 LAST OFFPAGE TRUE
J 0
(1175 -3225);
DISPLAY 0.872340 (1175 -3225);
PAINT GREEN (1175 -3225);
DISPLAY INVISIBLE (1175 -3225);
FORCEPROP 1 LAST COMMENT_BODY TRUE
J 0
(805 -3195);
DISPLAY 0.872340 (805 -3195);
PAINT GREEN (805 -3195);
DISPLAY INVISIBLE (805 -3195);
FORCEADD OFFPAGE..2
(850 -3500);
FORCEPROP 2 LAST $XR0 147 
J 0
(1039 -3500);
DISPLAY 0.638298 (1039 -3500);
PAINT MONO (1039 -3500);
FORCEPROP 2 LAST PATH I223
J 0
(1050 -3450);
DISPLAY 1.021277 (1050 -3450);
PAINT ORANGE (1050 -3450);
DISPLAY INVISIBLE (1050 -3450);
FORCEPROP 2 LAST CDS_LIB mstr_standard
J 0
(850 -3500);
PAINT MONO (850 -3500);
DISPLAY INVISIBLE (850 -3500);
FORCEPROP 1 LAST OFFPAGE TRUE
J 0
(1175 -3625);
DISPLAY 0.872340 (1175 -3625);
PAINT GREEN (1175 -3625);
DISPLAY INVISIBLE (1175 -3625);
FORCEPROP 1 LAST COMMENT_BODY TRUE
J 0
(805 -3595);
DISPLAY 0.872340 (805 -3595);
PAINT GREEN (805 -3595);
DISPLAY INVISIBLE (805 -3595);
FORCEADD OFFPAGE..2
(3150 400);
FORCEPROP 2 LAST $XR0 147 
J 0
(3339 400);
DISPLAY 0.638298 (3339 400);
PAINT MONO (3339 400);
FORCEPROP 2 LAST PATH I224
J 0
(3350 450);
DISPLAY 1.021277 (3350 450);
PAINT ORANGE (3350 450);
DISPLAY INVISIBLE (3350 450);
FORCEPROP 2 LAST CDS_LIB mstr_standard
J 0
(3150 400);
PAINT ORANGE (3150 400);
DISPLAY INVISIBLE (3150 400);
FORCEPROP 1 LAST OFFPAGE TRUE
J 0
(3475 275);
DISPLAY 0.872340 (3475 275);
PAINT GREEN (3475 275);
DISPLAY INVISIBLE (3475 275);
FORCEPROP 1 LAST COMMENT_BODY TRUE
J 0
(3105 305);
DISPLAY 0.872340 (3105 305);
PAINT GREEN (3105 305);
DISPLAY INVISIBLE (3105 305);
FORCEADD OFFPAGE..2
(3150 0);
FORCEPROP 2 LAST $XR0 147 
J 0
(3339 0);
DISPLAY 0.638298 (3339 0);
PAINT MONO (3339 0);
FORCEPROP 2 LAST CDS_LIB mstr_standard
J 0
(3150 0);
PAINT MONO (3150 0);
DISPLAY INVISIBLE (3150 0);
FORCEPROP 2 LAST PATH I225
J 0
(3350 50);
DISPLAY 1.021277 (3350 50);
PAINT ORANGE (3350 50);
DISPLAY INVISIBLE (3350 50);
FORCEPROP 1 LAST OFFPAGE TRUE
J 0
(3475 -125);
DISPLAY 0.872340 (3475 -125);
PAINT GREEN (3475 -125);
DISPLAY INVISIBLE (3475 -125);
FORCEPROP 1 LAST COMMENT_BODY TRUE
J 0
(3105 -95);
DISPLAY 0.872340 (3105 -95);
PAINT GREEN (3105 -95);
DISPLAY INVISIBLE (3105 -95);
FORCEADD GND..1
(-900 -2800);
FORCEPROP 3 LASTPIN (-900 -2750) SIG_NAME GND\g
J 0
(-890 -2740);
DISPLAY 0.659574 (-890 -2740);
PAINT MONO (-890 -2740);
DISPLAY INVISIBLE (-890 -2740);
FORCEPROP 2 LAST CDS_LIB mstr_symbols
J 0
(-900 -2800);
PAINT MONO (-900 -2800);
DISPLAY INVISIBLE (-900 -2800);
FORCEPROP 1 LAST SIZE 1B
J 0
(-825 -2850);
DISPLAY 0.872340 (-825 -2850);
PAINT AQUA (-825 -2850);
DISPLAY INVISIBLE (-825 -2850);
FORCEPROP 1 LAST VOLTAGE 0.0V
J 0
(-945 -2843);
DISPLAY 0.340426 (-945 -2843);
PAINT GREEN (-945 -2843);
DISPLAY INVISIBLE (-945 -2843);
FORCEPROP 1 LAST PATH I227
J 0
(-825 -2800);
DISPLAY 0.872340 (-825 -2800);
PAINT AQUA (-825 -2800);
DISPLAY INVISIBLE (-825 -2800);
FORCEPROP 1 LAST BODY_TYPE PLUMBING
J 0
(-945 -2843);
DISPLAY 0.340426 (-945 -2843);
PAINT GREEN (-945 -2843);
DISPLAY INVISIBLE (-945 -2843);
FORCEPROP 1 LAST HDL_POWER GND
J 0
(-900 -2650);
DISPLAY 0.872340 (-900 -2650);
PAINT GREEN (-900 -2650);
DISPLAY INVISIBLE (-900 -2650);
FORCEADD RES..1
(-600 -3100);
FORCEPROP 1 LAST VALUE 4.75K
J 2
(-550 -3050);
DISPLAY 0.617021 (-550 -3050);
PAINT SKYBLUE (-550 -3050);
FORCEPROP 1 LASTPIN (-500 -3100) $PN 2
J 0
(-538 -3088);
DISPLAY 0.787234 (-538 -3088);
PAINT ORANGE (-538 -3088);
FORCEPROP 1 LAST TOLERANCE 1%
J 0
(-525 -3050);
DISPLAY 0.617021 (-525 -3050);
PAINT SKYBLUE (-525 -3050);
FORCEPROP 1 LAST WATTAGE 1/16W
J 2
(-325 -3050);
DISPLAY 0.617021 (-325 -3050);
PAINT SKYBLUE (-325 -3050);
FORCEPROP 1 LAST LOCATION R25W112
J 0
(-850 -3050);
DISPLAY 0.617021 (-850 -3050);
PAINT AQUA (-850 -3050);
FORCEPROP 1 LAST MATERIAL EMPTY
J 0
(-850 -3100);
DISPLAY 0.617021 (-850 -3100);
PAINT RED (-850 -3100);
FORCEPROP 1 LASTPIN (-700 -3100) $PN 1
J 0
(-688 -3088);
DISPLAY 0.787234 (-688 -3088);
PAINT ORANGE (-688 -3088);
FORCEPROP 1 LAST PART_NUMBER G21796-072
J 0
(-450 -3100);
DISPLAY 0.617021 (-450 -3100);
PAINT BLUE (-450 -3100);
FORCEPROP 1 LAST PACK_TYPE 0402
J 0
(-200 -3100);
DISPLAY 0.617021 (-200 -3100);
PAINT SKYBLUE (-200 -3100);
FORCEPROP 2 LAST SEC_TYPE 0402
J 0
(-650 -2900);
DISPLAY 1.021277 (-650 -2900);
PAINT ORANGE (-650 -2900);
DISPLAY INVISIBLE (-650 -2900);
FORCEPROP 2 LAST SEC 1
J 0
(-650 -2900);
PAINT MONO (-650 -2900);
DISPLAY INVISIBLE (-650 -2900);
FORCEPROP 2 LAST CDS_LOCATION R25W112
J 0
(-650 -3050);
DISPLAY 0.617021 (-650 -3050);
PAINT AQUA (-650 -3050);
DISPLAY INVISIBLE (-650 -3050);
FORCEPROP 2 LAST CDS_LIB mstr_discrete
J 0
(-600 -3100);
PAINT ORANGE (-600 -3100);
DISPLAY INVISIBLE (-600 -3100);
FORCEPROP 2 LAST ROOM BMC
J 0
(-650 -3000);
DISPLAY 1.021277 (-650 -3000);
PAINT ORANGE (-650 -3000);
DISPLAY INVISIBLE (-650 -3000);
FORCEPROP 2 LAST BOM_COST SM_CONTROLLER
J 0
(-650 -2950);
DISPLAY 1.021277 (-650 -2950);
PAINT ORANGE (-650 -2950);
DISPLAY INVISIBLE (-650 -2950);
FORCEPROP 0 LAST CDS_SEC 1
J 0
(-325 -3000);
PAINT MONO (-325 -3000);
DISPLAY INVISIBLE (-325 -3000);
FORCEPROP 1 LAST PATH I228
J 0
(-650 -2950);
DISPLAY 0.978723 (-650 -2950);
PAINT WHITE (-650 -2950);
DISPLAY INVISIBLE (-650 -2950);
FORCEADD RES..1
(-600 -3300);
FORCEPROP 1 LAST TOLERANCE 1%
J 0
(-525 -3250);
DISPLAY 0.617021 (-525 -3250);
PAINT SKYBLUE (-525 -3250);
FORCEPROP 1 LASTPIN (-500 -3300) $PN 2
J 0
(-538 -3288);
DISPLAY 0.787234 (-538 -3288);
PAINT ORANGE (-538 -3288);
FORCEPROP 1 LAST VALUE 4.75K
J 0
(-650 -3250);
DISPLAY 0.617021 (-650 -3250);
PAINT SKYBLUE (-650 -3250);
FORCEPROP 1 LAST PART_NUMBER G21796-072
J 0
(-450 -3300);
DISPLAY 0.617021 (-450 -3300);
PAINT BLUE (-450 -3300);
FORCEPROP 1 LAST PACK_TYPE 0402
J 0
(-200 -3300);
DISPLAY 0.617021 (-200 -3300);
PAINT SKYBLUE (-200 -3300);
FORCEPROP 1 LAST WATTAGE 1/16W
J 0
(-450 -3250);
DISPLAY 0.617021 (-450 -3250);
PAINT SKYBLUE (-450 -3250);
FORCEPROP 1 LASTPIN (-700 -3300) $PN 1
J 0
(-688 -3288);
DISPLAY 0.787234 (-688 -3288);
PAINT ORANGE (-688 -3288);
FORCEPROP 1 LAST LOCATION R25W150
J 0
(-850 -3250);
DISPLAY 0.617021 (-850 -3250);
PAINT AQUA (-850 -3250);
FORCEPROP 1 LAST MATERIAL CHIP
J 0
(-850 -3300);
DISPLAY 0.617021 (-850 -3300);
PAINT SKYBLUE (-850 -3300);
FORCEPROP 1 LAST PATH I229
J 0
(-650 -3150);
DISPLAY 0.978723 (-650 -3150);
PAINT WHITE (-650 -3150);
DISPLAY INVISIBLE (-650 -3150);
FORCEPROP 2 LAST SEC 1
J 0
(-650 -3100);
DISPLAY 0.680851 (-650 -3100);
PAINT MONO (-650 -3100);
DISPLAY INVISIBLE (-650 -3100);
FORCEPROP 2 LAST SEC_TYPE 0402
J 0
(-650 -3100);
DISPLAY 1.021277 (-650 -3100);
PAINT ORANGE (-650 -3100);
DISPLAY INVISIBLE (-650 -3100);
FORCEPROP 2 LAST BOM_COST SM_CONTROLLER
J 0
(-650 -3150);
DISPLAY 1.021277 (-650 -3150);
PAINT ORANGE (-650 -3150);
DISPLAY INVISIBLE (-650 -3150);
FORCEPROP 2 LAST ROOM BMC
J 0
(-650 -3200);
DISPLAY 1.021277 (-650 -3200);
PAINT ORANGE (-650 -3200);
DISPLAY INVISIBLE (-650 -3200);
FORCEPROP 2 LAST CDS_LIB mstr_discrete
J 0
(-600 -3300);
PAINT MONO (-600 -3300);
DISPLAY INVISIBLE (-600 -3300);
FORCEADD RES..1
(-600 -3500);
FORCEPROP 1 LAST PACK_TYPE 0402
J 0
(-200 -3500);
DISPLAY 0.617021 (-200 -3500);
PAINT SKYBLUE (-200 -3500);
FORCEPROP 1 LAST PART_NUMBER G21796-072
J 0
(-450 -3500);
DISPLAY 0.617021 (-450 -3500);
PAINT BLUE (-450 -3500);
FORCEPROP 1 LAST WATTAGE 1/16W
J 2
(-325 -3450);
DISPLAY 0.617021 (-325 -3450);
PAINT SKYBLUE (-325 -3450);
FORCEPROP 1 LASTPIN (-500 -3500) $PN 2
J 0
(-538 -3488);
DISPLAY 0.787234 (-538 -3488);
PAINT ORANGE (-538 -3488);
FORCEPROP 1 LAST TOLERANCE 1%
J 0
(-525 -3450);
DISPLAY 0.617021 (-525 -3450);
PAINT SKYBLUE (-525 -3450);
FORCEPROP 1 LAST VALUE 4.75K
J 2
(-550 -3450);
DISPLAY 0.617021 (-550 -3450);
PAINT SKYBLUE (-550 -3450);
FORCEPROP 1 LASTPIN (-700 -3500) $PN 1
J 0
(-688 -3488);
DISPLAY 0.787234 (-688 -3488);
PAINT ORANGE (-688 -3488);
FORCEPROP 1 LAST LOCATION R25W113
J 0
(-850 -3450);
DISPLAY 0.617021 (-850 -3450);
PAINT AQUA (-850 -3450);
FORCEPROP 1 LAST MATERIAL EMPTY
J 0
(-850 -3500);
DISPLAY 0.617021 (-850 -3500);
PAINT RED (-850 -3500);
FORCEPROP 1 LAST PATH I230
J 0
(-650 -3350);
DISPLAY 0.978723 (-650 -3350);
PAINT WHITE (-650 -3350);
DISPLAY INVISIBLE (-650 -3350);
FORCEPROP 0 LAST CDS_SEC 1
J 0
(-325 -3400);
PAINT MONO (-325 -3400);
DISPLAY INVISIBLE (-325 -3400);
FORCEPROP 2 LAST BOM_COST SM_CONTROLLER
J 0
(-650 -3350);
DISPLAY 1.021277 (-650 -3350);
PAINT ORANGE (-650 -3350);
DISPLAY INVISIBLE (-650 -3350);
FORCEPROP 2 LAST ROOM BMC
J 0
(-650 -3400);
DISPLAY 1.021277 (-650 -3400);
PAINT ORANGE (-650 -3400);
DISPLAY INVISIBLE (-650 -3400);
FORCEPROP 2 LAST CDS_LIB mstr_discrete
J 0
(-600 -3500);
PAINT ORANGE (-600 -3500);
DISPLAY INVISIBLE (-600 -3500);
FORCEPROP 2 LAST CDS_LOCATION R25W113
J 0
(-650 -3450);
DISPLAY 0.617021 (-650 -3450);
PAINT AQUA (-650 -3450);
DISPLAY INVISIBLE (-650 -3450);
FORCEPROP 2 LAST SEC 1
J 0
(-650 -3300);
PAINT MONO (-650 -3300);
DISPLAY INVISIBLE (-650 -3300);
FORCEPROP 2 LAST SEC_TYPE 0402
J 0
(-650 -3300);
DISPLAY 1.021277 (-650 -3300);
PAINT ORANGE (-650 -3300);
DISPLAY INVISIBLE (-650 -3300);
FORCEADD GND..1
(-900 -3400);
FORCEPROP 3 LASTPIN (-900 -3350) SIG_NAME GND\g
J 0
(-890 -3340);
DISPLAY 0.659574 (-890 -3340);
PAINT MONO (-890 -3340);
DISPLAY INVISIBLE (-890 -3340);
FORCEPROP 1 LAST PATH I231
J 0
(-825 -3400);
DISPLAY 0.872340 (-825 -3400);
PAINT AQUA (-825 -3400);
DISPLAY INVISIBLE (-825 -3400);
FORCEPROP 2 LAST CDS_LIB mstr_symbols
J 0
(-900 -3400);
PAINT MONO (-900 -3400);
DISPLAY INVISIBLE (-900 -3400);
FORCEPROP 1 LAST SIZE 1B
J 0
(-825 -3450);
DISPLAY 0.872340 (-825 -3450);
PAINT AQUA (-825 -3450);
DISPLAY INVISIBLE (-825 -3450);
FORCEPROP 1 LAST VOLTAGE 0.0V
J 0
(-945 -3443);
DISPLAY 0.340426 (-945 -3443);
PAINT GREEN (-945 -3443);
DISPLAY INVISIBLE (-945 -3443);
FORCEPROP 1 LAST BODY_TYPE PLUMBING
J 0
(-945 -3443);
DISPLAY 0.340426 (-945 -3443);
PAINT GREEN (-945 -3443);
DISPLAY INVISIBLE (-945 -3443);
FORCEPROP 1 LAST HDL_POWER GND
J 0
(-900 -3250);
DISPLAY 0.872340 (-900 -3250);
PAINT GREEN (-900 -3250);
DISPLAY INVISIBLE (-900 -3250);
FORCEADD RES..1
(-600 -3650);
FORCEPROP 1 LAST PACK_TYPE 0402
J 0
(-200 -3650);
DISPLAY 0.617021 (-200 -3650);
PAINT SKYBLUE (-200 -3650);
FORCEPROP 1 LAST PART_NUMBER G21796-072
J 0
(-450 -3650);
DISPLAY 0.617021 (-450 -3650);
PAINT BLUE (-450 -3650);
FORCEPROP 1 LAST WATTAGE 1/16W
J 0
(-450 -3600);
DISPLAY 0.617021 (-450 -3600);
PAINT SKYBLUE (-450 -3600);
FORCEPROP 1 LAST TOLERANCE 1%
J 0
(-525 -3600);
DISPLAY 0.617021 (-525 -3600);
PAINT SKYBLUE (-525 -3600);
FORCEPROP 1 LAST VALUE 4.75K
J 0
(-650 -3600);
DISPLAY 0.617021 (-650 -3600);
PAINT SKYBLUE (-650 -3600);
FORCEPROP 1 LASTPIN (-500 -3650) $PN 2
J 0
(-538 -3638);
DISPLAY 0.787234 (-538 -3638);
PAINT ORANGE (-538 -3638);
FORCEPROP 1 LASTPIN (-700 -3650) $PN 1
J 0
(-688 -3638);
DISPLAY 0.787234 (-688 -3638);
PAINT ORANGE (-688 -3638);
FORCEPROP 1 LAST LOCATION R25W151
J 0
(-850 -3600);
DISPLAY 0.617021 (-850 -3600);
PAINT AQUA (-850 -3600);
FORCEPROP 1 LAST MATERIAL CHIP
J 0
(-850 -3650);
DISPLAY 0.617021 (-850 -3650);
PAINT SKYBLUE (-850 -3650);
FORCEPROP 1 LAST PATH I232
J 0
(-650 -3500);
DISPLAY 0.978723 (-650 -3500);
PAINT WHITE (-650 -3500);
DISPLAY INVISIBLE (-650 -3500);
FORCEPROP 2 LAST CDS_LIB mstr_discrete
J 0
(-600 -3650);
PAINT MONO (-600 -3650);
DISPLAY INVISIBLE (-600 -3650);
FORCEPROP 2 LAST ROOM BMC
J 0
(-650 -3550);
DISPLAY 1.021277 (-650 -3550);
PAINT ORANGE (-650 -3550);
DISPLAY INVISIBLE (-650 -3550);
FORCEPROP 2 LAST BOM_COST SM_CONTROLLER
J 0
(-650 -3500);
DISPLAY 1.021277 (-650 -3500);
PAINT ORANGE (-650 -3500);
DISPLAY INVISIBLE (-650 -3500);
FORCEPROP 2 LAST SEC_TYPE 0402
J 0
(-650 -3450);
DISPLAY 1.021277 (-650 -3450);
PAINT ORANGE (-650 -3450);
DISPLAY INVISIBLE (-650 -3450);
FORCEPROP 2 LAST SEC 1
J 0
(-650 -3450);
DISPLAY 0.680851 (-650 -3450);
PAINT MONO (-650 -3450);
DISPLAY INVISIBLE (-650 -3450);
FORCEADD RES..1
(1850 400);
FORCEPROP 1 LAST MATERIAL EMPTY
J 0
(1600 400);
DISPLAY 0.617021 (1600 400);
PAINT RED (1600 400);
FORCEPROP 1 LAST VALUE 4.75K
J 2
(1900 450);
DISPLAY 0.617021 (1900 450);
PAINT SKYBLUE (1900 450);
FORCEPROP 1 LAST TOLERANCE 1%
J 0
(1925 450);
DISPLAY 0.617021 (1925 450);
PAINT SKYBLUE (1925 450);
FORCEPROP 1 LASTPIN (1950 400) $PN 2
J 0
(1912 412);
DISPLAY 0.787234 (1912 412);
PAINT ORANGE (1912 412);
FORCEPROP 1 LASTPIN (1750 400) $PN 1
J 0
(1762 412);
DISPLAY 0.787234 (1762 412);
PAINT ORANGE (1762 412);
FORCEPROP 1 LAST PART_NUMBER G21796-072
J 0
(2000 400);
DISPLAY 0.617021 (2000 400);
PAINT BLUE (2000 400);
FORCEPROP 1 LAST WATTAGE 1/16W
J 2
(2125 450);
DISPLAY 0.617021 (2125 450);
PAINT SKYBLUE (2125 450);
FORCEPROP 1 LAST PACK_TYPE 0402
J 0
(2250 400);
DISPLAY 0.617021 (2250 400);
PAINT SKYBLUE (2250 400);
FORCEPROP 1 LAST LOCATION R25W110
J 0
(1600 450);
DISPLAY 0.617021 (1600 450);
PAINT AQUA (1600 450);
FORCEPROP 2 LAST CDS_LOCATION R25W110
J 0
(1800 450);
DISPLAY 0.617021 (1800 450);
PAINT AQUA (1800 450);
DISPLAY INVISIBLE (1800 450);
FORCEPROP 2 LAST SEC_TYPE 0402
J 0
(1800 600);
DISPLAY 1.021277 (1800 600);
PAINT ORANGE (1800 600);
DISPLAY INVISIBLE (1800 600);
FORCEPROP 2 LAST SEC 1
J 0
(1800 600);
PAINT MONO (1800 600);
DISPLAY INVISIBLE (1800 600);
FORCEPROP 2 LAST CDS_LIB mstr_discrete
J 0
(1850 400);
PAINT ORANGE (1850 400);
DISPLAY INVISIBLE (1850 400);
FORCEPROP 2 LAST ROOM BMC
J 0
(1800 500);
DISPLAY 1.021277 (1800 500);
PAINT ORANGE (1800 500);
DISPLAY INVISIBLE (1800 500);
FORCEPROP 2 LAST BOM_COST SM_CONTROLLER
J 0
(1800 550);
DISPLAY 1.021277 (1800 550);
PAINT ORANGE (1800 550);
DISPLAY INVISIBLE (1800 550);
FORCEPROP 0 LAST CDS_SEC 1
J 0
(2125 500);
PAINT MONO (2125 500);
DISPLAY INVISIBLE (2125 500);
FORCEPROP 1 LAST PATH I233
J 0
(1800 550);
DISPLAY 0.978723 (1800 550);
PAINT WHITE (1800 550);
DISPLAY INVISIBLE (1800 550);
FORCEADD RES..1
(1850 200);
FORCEPROP 1 LAST PACK_TYPE 0402
J 0
(2250 200);
DISPLAY 0.617021 (2250 200);
PAINT SKYBLUE (2250 200);
FORCEPROP 1 LAST TOLERANCE 1%
J 0
(1925 250);
DISPLAY 0.617021 (1925 250);
PAINT SKYBLUE (1925 250);
FORCEPROP 1 LASTPIN (1750 200) $PN 1
J 0
(1762 212);
DISPLAY 0.787234 (1762 212);
PAINT ORANGE (1762 212);
FORCEPROP 1 LASTPIN (1950 200) $PN 2
J 0
(1912 212);
DISPLAY 0.787234 (1912 212);
PAINT ORANGE (1912 212);
FORCEPROP 1 LAST VALUE 4.75K
J 0
(1800 250);
DISPLAY 0.617021 (1800 250);
PAINT SKYBLUE (1800 250);
FORCEPROP 1 LAST LOCATION R25W152
J 0
(1600 250);
DISPLAY 0.617021 (1600 250);
PAINT AQUA (1600 250);
FORCEPROP 1 LAST WATTAGE 1/16W
J 0
(2000 250);
DISPLAY 0.617021 (2000 250);
PAINT SKYBLUE (2000 250);
FORCEPROP 1 LAST PART_NUMBER G21796-072
J 0
(2000 200);
DISPLAY 0.617021 (2000 200);
PAINT BLUE (2000 200);
FORCEPROP 1 LAST MATERIAL CHIP
J 0
(1600 200);
DISPLAY 0.617021 (1600 200);
PAINT SKYBLUE (1600 200);
FORCEPROP 1 LAST PATH I234
J 0
(1800 350);
DISPLAY 0.978723 (1800 350);
PAINT WHITE (1800 350);
DISPLAY INVISIBLE (1800 350);
FORCEPROP 2 LAST CDS_LIB mstr_discrete
J 0
(1850 200);
PAINT MONO (1850 200);
DISPLAY INVISIBLE (1850 200);
FORCEPROP 2 LAST ROOM BMC
J 0
(1800 300);
DISPLAY 1.021277 (1800 300);
PAINT ORANGE (1800 300);
DISPLAY INVISIBLE (1800 300);
FORCEPROP 2 LAST BOM_COST SM_CONTROLLER
J 0
(1800 350);
DISPLAY 1.021277 (1800 350);
PAINT ORANGE (1800 350);
DISPLAY INVISIBLE (1800 350);
FORCEPROP 2 LAST SEC_TYPE 0402
J 0
(1800 400);
DISPLAY 1.021277 (1800 400);
PAINT ORANGE (1800 400);
DISPLAY INVISIBLE (1800 400);
FORCEPROP 2 LAST SEC 1
J 0
(1800 400);
DISPLAY 0.680851 (1800 400);
PAINT MONO (1800 400);
DISPLAY INVISIBLE (1800 400);
FORCEADD GND..1
(-900 -3750);
FORCEPROP 3 LASTPIN (-900 -3700) SIG_NAME GND\g
J 0
(-890 -3690);
DISPLAY 0.659574 (-890 -3690);
PAINT MONO (-890 -3690);
DISPLAY INVISIBLE (-890 -3690);
FORCEPROP 1 LAST PATH I235
J 0
(-825 -3750);
DISPLAY 0.872340 (-825 -3750);
PAINT AQUA (-825 -3750);
DISPLAY INVISIBLE (-825 -3750);
FORCEPROP 2 LAST CDS_LIB mstr_symbols
J 0
(-900 -3750);
PAINT MONO (-900 -3750);
DISPLAY INVISIBLE (-900 -3750);
FORCEPROP 1 LAST SIZE 1B
J 0
(-825 -3800);
DISPLAY 0.872340 (-825 -3800);
PAINT AQUA (-825 -3800);
DISPLAY INVISIBLE (-825 -3800);
FORCEPROP 1 LAST VOLTAGE 0.0V
J 0
(-945 -3793);
DISPLAY 0.340426 (-945 -3793);
PAINT GREEN (-945 -3793);
DISPLAY INVISIBLE (-945 -3793);
FORCEPROP 1 LAST BODY_TYPE PLUMBING
J 0
(-945 -3793);
DISPLAY 0.340426 (-945 -3793);
PAINT GREEN (-945 -3793);
DISPLAY INVISIBLE (-945 -3793);
FORCEPROP 1 LAST HDL_POWER GND
J 0
(-900 -3600);
DISPLAY 0.872340 (-900 -3600);
PAINT GREEN (-900 -3600);
DISPLAY INVISIBLE (-900 -3600);
FORCEADD RES..1
(1850 0);
FORCEPROP 1 LAST PART_NUMBER G21796-072
J 0
(2000 0);
DISPLAY 0.617021 (2000 0);
PAINT BLUE (2000 0);
FORCEPROP 1 LAST TOLERANCE 1%
J 0
(1925 50);
DISPLAY 0.617021 (1925 50);
PAINT SKYBLUE (1925 50);
FORCEPROP 1 LAST LOCATION R25W109
J 0
(1600 50);
DISPLAY 0.617021 (1600 50);
PAINT AQUA (1600 50);
FORCEPROP 1 LAST MATERIAL CHIP
J 0
(1600 0);
DISPLAY 0.617021 (1600 0);
PAINT SKYBLUE (1600 0);
FORCEPROP 1 LAST VALUE 4.75K
J 0
(1800 50);
DISPLAY 0.617021 (1800 50);
PAINT SKYBLUE (1800 50);
FORCEPROP 1 LASTPIN (1750 0) $PN 1
J 0
(1762 12);
DISPLAY 0.787234 (1762 12);
PAINT ORANGE (1762 12);
FORCEPROP 1 LASTPIN (1950 0) $PN 2
J 0
(1912 12);
DISPLAY 0.787234 (1912 12);
PAINT ORANGE (1912 12);
FORCEPROP 1 LAST PACK_TYPE 0402
J 0
(2250 0);
DISPLAY 0.617021 (2250 0);
PAINT SKYBLUE (2250 0);
FORCEPROP 1 LAST WATTAGE 1/16W
J 0
(2000 50);
DISPLAY 0.617021 (2000 50);
PAINT SKYBLUE (2000 50);
FORCEPROP 1 LAST PATH I236
J 0
(1800 150);
DISPLAY 0.978723 (1800 150);
PAINT WHITE (1800 150);
DISPLAY INVISIBLE (1800 150);
FORCEPROP 2 LAST CDS_LIB mstr_discrete
J 0
(1850 0);
PAINT MONO (1850 0);
DISPLAY INVISIBLE (1850 0);
FORCEPROP 2 LAST ROOM BMC
J 0
(1800 100);
DISPLAY 1.021277 (1800 100);
PAINT ORANGE (1800 100);
DISPLAY INVISIBLE (1800 100);
FORCEPROP 2 LAST BOM_COST SM_CONTROLLER
J 0
(1800 150);
DISPLAY 1.021277 (1800 150);
PAINT ORANGE (1800 150);
DISPLAY INVISIBLE (1800 150);
FORCEPROP 2 LAST SEC_TYPE 0402
J 0
(1800 200);
DISPLAY 1.021277 (1800 200);
PAINT ORANGE (1800 200);
DISPLAY INVISIBLE (1800 200);
FORCEPROP 2 LAST SEC 1
J 0
(1800 200);
DISPLAY 0.680851 (1800 200);
PAINT MONO (1800 200);
DISPLAY INVISIBLE (1800 200);
FORCEADD GND..1
(1550 100);
FORCEPROP 3 LASTPIN (1550 150) SIG_NAME GND\g
J 0
(1560 160);
DISPLAY 0.659574 (1560 160);
PAINT MONO (1560 160);
DISPLAY INVISIBLE (1560 160);
FORCEPROP 1 LAST PATH I237
J 0
(1625 100);
DISPLAY 0.872340 (1625 100);
PAINT AQUA (1625 100);
DISPLAY INVISIBLE (1625 100);
FORCEPROP 1 LAST VOLTAGE 0.0V
J 0
(1505 57);
DISPLAY 0.340426 (1505 57);
PAINT GREEN (1505 57);
DISPLAY INVISIBLE (1505 57);
FORCEPROP 1 LAST SIZE 1B
J 0
(1625 50);
DISPLAY 0.872340 (1625 50);
PAINT AQUA (1625 50);
DISPLAY INVISIBLE (1625 50);
FORCEPROP 2 LAST CDS_LIB mstr_symbols
J 0
(1550 100);
PAINT MONO (1550 100);
DISPLAY INVISIBLE (1550 100);
FORCEPROP 1 LAST BODY_TYPE PLUMBING
J 0
(1505 57);
DISPLAY 0.340426 (1505 57);
PAINT GREEN (1505 57);
DISPLAY INVISIBLE (1505 57);
FORCEPROP 1 LAST HDL_POWER GND
J 0
(1550 250);
DISPLAY 0.872340 (1550 250);
PAINT GREEN (1550 250);
DISPLAY INVISIBLE (1550 250);
FORCEADD P3V3_STBY..1
(1450 550);
FORCEPROP 3 LASTPIN (1450 500) SIG_NAME P3V3_STBY\g
J 0
(1460 510);
DISPLAY 0.659574 (1460 510);
PAINT MONO (1460 510);
DISPLAY INVISIBLE (1460 510);
FORCEPROP 1 LAST PATH I238
J 0
(1495 552);
DISPLAY 0.340426 (1495 552);
PAINT GREEN (1495 552);
DISPLAY INVISIBLE (1495 552);
FORCEPROP 1 LAST SIZE 1B
J 0
(1495 572);
DISPLAY 0.340426 (1495 572);
PAINT GREEN (1495 572);
DISPLAY INVISIBLE (1495 572);
FORCEPROP 1 LAST VOLTAGE 3.3V
J 0
(1405 507);
DISPLAY 0.340426 (1405 507);
PAINT SKYBLUE (1405 507);
DISPLAY INVISIBLE (1405 507);
FORCEPROP 2 LAST CDS_LIB mstr_symbols
J 0
(1450 550);
PAINT ORANGE (1450 550);
DISPLAY INVISIBLE (1450 550);
FORCEPROP 1 LAST BODY_TYPE PLUMBING
J 0
(1405 507);
DISPLAY 0.340426 (1405 507);
PAINT GREEN (1405 507);
DISPLAY INVISIBLE (1405 507);
FORCEPROP 1 LAST HDL_POWER P3V3_STBY
J 0
(1150 425);
DISPLAY 0.872340 (1150 425);
PAINT ORANGE (1150 425);
DISPLAY INVISIBLE (1150 425);
FORCEADD RES..1
(1850 -1000);
FORCEPROP 1 LAST PACK_TYPE 0402
J 0
(2250 -1000);
DISPLAY 0.617021 (2250 -1000);
PAINT SKYBLUE (2250 -1000);
FORCEPROP 1 LAST WATTAGE 1/16W
J 2
(2125 -950);
DISPLAY 0.617021 (2125 -950);
PAINT SKYBLUE (2125 -950);
FORCEPROP 1 LAST TOLERANCE 1%
J 0
(1925 -950);
DISPLAY 0.617021 (1925 -950);
PAINT SKYBLUE (1925 -950);
FORCEPROP 1 LASTPIN (1750 -1000) $PN 1
J 0
(1762 -988);
DISPLAY 0.787234 (1762 -988);
PAINT ORANGE (1762 -988);
FORCEPROP 1 LAST LOCATION R25W102
J 0
(1600 -950);
DISPLAY 0.617021 (1600 -950);
PAINT AQUA (1600 -950);
FORCEPROP 1 LAST PART_NUMBER G21796-072
J 0
(2000 -1000);
DISPLAY 0.617021 (2000 -1000);
PAINT BLUE (2000 -1000);
FORCEPROP 1 LAST MATERIAL EMPTY
J 0
(1600 -1000);
DISPLAY 0.617021 (1600 -1000);
PAINT RED (1600 -1000);
FORCEPROP 1 LASTPIN (1950 -1000) $PN 2
J 0
(1912 -988);
DISPLAY 0.787234 (1912 -988);
PAINT ORANGE (1912 -988);
FORCEPROP 1 LAST VALUE 4.75K
J 2
(1900 -950);
DISPLAY 0.617021 (1900 -950);
PAINT SKYBLUE (1900 -950);
FORCEPROP 2 LAST CDS_LOCATION R25W102
J 0
(1800 -950);
DISPLAY 0.617021 (1800 -950);
PAINT AQUA (1800 -950);
DISPLAY INVISIBLE (1800 -950);
FORCEPROP 2 LAST BOM_COST SM_CONTROLLER
J 0
(1800 -850);
DISPLAY 1.021277 (1800 -850);
PAINT ORANGE (1800 -850);
DISPLAY INVISIBLE (1800 -850);
FORCEPROP 2 LAST ROOM BMC
J 0
(1800 -900);
DISPLAY 1.021277 (1800 -900);
PAINT ORANGE (1800 -900);
DISPLAY INVISIBLE (1800 -900);
FORCEPROP 2 LAST CDS_LIB mstr_discrete
J 0
(1850 -1000);
PAINT ORANGE (1850 -1000);
DISPLAY INVISIBLE (1850 -1000);
FORCEPROP 2 LAST SEC 1
J 0
(1800 -800);
PAINT MONO (1800 -800);
DISPLAY INVISIBLE (1800 -800);
FORCEPROP 2 LAST SEC_TYPE 0402
J 0
(1800 -800);
DISPLAY 1.021277 (1800 -800);
PAINT ORANGE (1800 -800);
DISPLAY INVISIBLE (1800 -800);
FORCEPROP 0 LAST CDS_SEC 1
J 0
(2125 -900);
PAINT MONO (2125 -900);
DISPLAY INVISIBLE (2125 -900);
FORCEPROP 1 LAST PATH I239
J 0
(1800 -850);
DISPLAY 0.978723 (1800 -850);
PAINT WHITE (1800 -850);
DISPLAY INVISIBLE (1800 -850);
FORCEADD RES..2
R 1
(-600 -650);
FORCEPROP 1 LASTPIN (-700 -650) $PN 1
J 0
(-712 -645);
DISPLAY 0.617021 (-712 -645);
PAINT ORANGE (-712 -645);
FORCEPROP 1 LAST LOCATION R25W156
J 0
(-850 -580);
DISPLAY 0.617021 (-850 -580);
PAINT AQUA (-850 -580);
FORCEPROP 1 LASTPIN (-500 -650) $PN 2
J 0
(-510 -645);
DISPLAY 0.617021 (-510 -645);
PAINT ORANGE (-510 -645);
FORCEPROP 1 LAST WATTAGE 1/16W
J 0
(-450 -585);
DISPLAY 0.617021 (-450 -585);
PAINT SKYBLUE (-450 -585);
FORCEPROP 1 LAST VALUE 3.32K
J 0
(-650 -605);
DISPLAY 0.617021 (-650 -605);
PAINT SKYBLUE (-650 -605);
FORCEPROP 1 LAST MATERIAL EMPTY
J 0
(-850 -635);
DISPLAY 0.617021 (-850 -635);
PAINT RED (-850 -635);
FORCEPROP 1 LAST PACK_TYPE 0402
J 0
(-200 -635);
DISPLAY 0.617021 (-200 -635);
PAINT SKYBLUE (-200 -635);
FORCEPROP 1 LAST TOLERANCE 1%
J 0
(-525 -605);
DISPLAY 0.617021 (-525 -605);
PAINT SKYBLUE (-525 -605);
FORCEPROP 1 LAST PART_NUMBER G21796-027
J 0
(-450 -635);
DISPLAY 0.617021 (-450 -635);
PAINT BLUE (-450 -635);
FORCEPROP 2 LAST CDS_LIB mstr_discrete
R 1
J 0
(-600 -650);
PAINT ORANGE (-600 -650);
DISPLAY INVISIBLE (-600 -650);
FORCEPROP 2 LAST ROOM NIC_SPRV
R 1
J 0
(-775 -600);
DISPLAY 1.021277 (-775 -600);
PAINT ORANGE (-775 -600);
DISPLAY INVISIBLE (-775 -600);
FORCEPROP 2 LAST BOM_COST NT_GBE_BASE
R 1
J 0
(-825 -600);
DISPLAY 1.021277 (-825 -600);
PAINT ORANGE (-825 -600);
DISPLAY INVISIBLE (-825 -600);
FORCEPROP 2 LAST SEC_TYPE 0402
R 1
J 0
(-825 -600);
DISPLAY 1.021277 (-825 -600);
PAINT ORANGE (-825 -600);
DISPLAY INVISIBLE (-825 -600);
FORCEPROP 2 LAST SEC 1
R 1
J 0
(-825 -600);
PAINT MONO (-825 -600);
DISPLAY INVISIBLE (-825 -600);
FORCEPROP 1 LAST PATH I240
R 1
J 0
(-775 -600);
DISPLAY 0.978723 (-775 -600);
PAINT WHITE (-775 -600);
DISPLAY INVISIBLE (-775 -600);
FORCEPROP 2 LAST CDS_LOCATION R25W156
R 1
J 0
(-725 -605);
DISPLAY 0.617021 (-725 -605);
PAINT AQUA (-725 -605);
DISPLAY INVISIBLE (-725 -605);
FORCEADD RES..1
(1850 -800);
FORCEPROP 1 LAST MATERIAL EMPTY
J 0
(1600 -800);
DISPLAY 0.617021 (1600 -800);
PAINT RED (1600 -800);
FORCEPROP 1 LAST PART_NUMBER G21796-072
J 0
(2000 -800);
DISPLAY 0.617021 (2000 -800);
PAINT BLUE (2000 -800);
FORCEPROP 1 LASTPIN (1750 -800) $PN 1
J 0
(1762 -788);
DISPLAY 0.787234 (1762 -788);
PAINT ORANGE (1762 -788);
FORCEPROP 1 LAST VALUE 4.75K
J 2
(1900 -750);
DISPLAY 0.617021 (1900 -750);
PAINT SKYBLUE (1900 -750);
FORCEPROP 1 LAST PACK_TYPE 0402
J 0
(2250 -800);
DISPLAY 0.617021 (2250 -800);
PAINT SKYBLUE (2250 -800);
FORCEPROP 1 LAST LOCATION R25W101
J 0
(1600 -750);
DISPLAY 0.617021 (1600 -750);
PAINT AQUA (1600 -750);
FORCEPROP 1 LAST WATTAGE 1/16W
J 2
(2125 -750);
DISPLAY 0.617021 (2125 -750);
PAINT SKYBLUE (2125 -750);
FORCEPROP 1 LAST TOLERANCE 1%
J 0
(1925 -750);
DISPLAY 0.617021 (1925 -750);
PAINT SKYBLUE (1925 -750);
FORCEPROP 1 LASTPIN (1950 -800) $PN 2
J 0
(1912 -788);
DISPLAY 0.787234 (1912 -788);
PAINT ORANGE (1912 -788);
FORCEPROP 2 LAST CDS_LOCATION R25W101
J 0
(1800 -750);
DISPLAY 0.617021 (1800 -750);
PAINT AQUA (1800 -750);
DISPLAY INVISIBLE (1800 -750);
FORCEPROP 0 LAST CDS_SEC 1
J 0
(2125 -700);
PAINT MONO (2125 -700);
DISPLAY INVISIBLE (2125 -700);
FORCEPROP 2 LAST SEC_TYPE 0402
J 0
(1800 -600);
DISPLAY 1.021277 (1800 -600);
PAINT ORANGE (1800 -600);
DISPLAY INVISIBLE (1800 -600);
FORCEPROP 2 LAST SEC 1
J 0
(1800 -600);
PAINT MONO (1800 -600);
DISPLAY INVISIBLE (1800 -600);
FORCEPROP 2 LAST CDS_LIB mstr_discrete
J 0
(1850 -800);
PAINT ORANGE (1850 -800);
DISPLAY INVISIBLE (1850 -800);
FORCEPROP 2 LAST ROOM BMC
J 0
(1800 -700);
DISPLAY 1.021277 (1800 -700);
PAINT ORANGE (1800 -700);
DISPLAY INVISIBLE (1800 -700);
FORCEPROP 2 LAST BOM_COST SM_CONTROLLER
J 0
(1800 -650);
DISPLAY 1.021277 (1800 -650);
PAINT ORANGE (1800 -650);
DISPLAY INVISIBLE (1800 -650);
FORCEPROP 1 LAST PATH I241
J 0
(1800 -650);
DISPLAY 0.978723 (1800 -650);
PAINT WHITE (1800 -650);
DISPLAY INVISIBLE (1800 -650);
FORCEADD RES..1
(-600 -2900);
FORCEPROP 1 LAST LOCATION R25W115
J 0
(-850 -2850);
DISPLAY 0.617021 (-850 -2850);
PAINT AQUA (-850 -2850);
FORCEPROP 1 LAST MATERIAL EMPTY
J 0
(-850 -2900);
DISPLAY 0.617021 (-850 -2900);
PAINT RED (-850 -2900);
FORCEPROP 1 LASTPIN (-700 -2900) $PN 1
J 0
(-688 -2888);
DISPLAY 0.787234 (-688 -2888);
PAINT ORANGE (-688 -2888);
FORCEPROP 1 LAST VALUE 4.75K
J 2
(-550 -2850);
DISPLAY 0.617021 (-550 -2850);
PAINT SKYBLUE (-550 -2850);
FORCEPROP 1 LASTPIN (-500 -2900) $PN 2
J 0
(-538 -2888);
DISPLAY 0.787234 (-538 -2888);
PAINT ORANGE (-538 -2888);
FORCEPROP 1 LAST TOLERANCE 1%
J 0
(-525 -2850);
DISPLAY 0.617021 (-525 -2850);
PAINT SKYBLUE (-525 -2850);
FORCEPROP 1 LAST WATTAGE 1/16W
J 2
(-325 -2850);
DISPLAY 0.617021 (-325 -2850);
PAINT SKYBLUE (-325 -2850);
FORCEPROP 1 LAST PART_NUMBER G21796-072
J 0
(-450 -2900);
DISPLAY 0.617021 (-450 -2900);
PAINT BLUE (-450 -2900);
FORCEPROP 1 LAST PACK_TYPE 0402
J 0
(-200 -2900);
DISPLAY 0.617021 (-200 -2900);
PAINT SKYBLUE (-200 -2900);
FORCEPROP 2 LAST CDS_LOCATION R25W115
J 0
(-650 -2850);
DISPLAY 0.617021 (-650 -2850);
PAINT AQUA (-650 -2850);
DISPLAY INVISIBLE (-650 -2850);
FORCEPROP 1 LAST PATH I242
J 0
(-650 -2750);
DISPLAY 0.978723 (-650 -2750);
PAINT WHITE (-650 -2750);
DISPLAY INVISIBLE (-650 -2750);
FORCEPROP 2 LAST SEC_TYPE 0402
J 0
(-650 -2700);
DISPLAY 1.021277 (-650 -2700);
PAINT ORANGE (-650 -2700);
DISPLAY INVISIBLE (-650 -2700);
FORCEPROP 2 LAST SEC 1
J 0
(-650 -2700);
PAINT MONO (-650 -2700);
DISPLAY INVISIBLE (-650 -2700);
FORCEPROP 2 LAST CDS_LIB mstr_discrete
J 0
(-600 -2900);
PAINT ORANGE (-600 -2900);
DISPLAY INVISIBLE (-600 -2900);
FORCEPROP 2 LAST ROOM BMC
J 0
(-650 -2800);
DISPLAY 1.021277 (-650 -2800);
PAINT ORANGE (-650 -2800);
DISPLAY INVISIBLE (-650 -2800);
FORCEPROP 2 LAST BOM_COST SM_CONTROLLER
J 0
(-650 -2750);
DISPLAY 1.021277 (-650 -2750);
PAINT ORANGE (-650 -2750);
DISPLAY INVISIBLE (-650 -2750);
FORCEPROP 0 LAST CDS_SEC 1
J 0
(-325 -2800);
PAINT MONO (-325 -2800);
DISPLAY INVISIBLE (-325 -2800);
FORCEADD DNS..2
(1855 -1180);
PAINT RED (1855 -1180);
FORCEPROP 2 LAST CDS_LIB mstr_misc
J 0
(1855 -1180);
PAINT ORANGE (1855 -1180);
DISPLAY INVISIBLE (1855 -1180);
FORCEPROP 1 LAST COMMENT_BODY TRUE
R 1
J 0
(1930 -1405);
DISPLAY 0.872340 (1930 -1405);
PAINT GREEN (1930 -1405);
DISPLAY INVISIBLE (1930 -1405);
FORCEADD DNS..2
(-595 -630);
PAINT RED (-595 -630);
FORCEPROP 2 LAST CDS_LIB mstr_misc
J 0
(-595 -630);
PAINT ORANGE (-595 -630);
DISPLAY INVISIBLE (-595 -630);
FORCEPROP 1 LAST COMMENT_BODY TRUE
R 1
J 0
(-520 -855);
DISPLAY 0.872340 (-520 -855);
PAINT GREEN (-520 -855);
DISPLAY INVISIBLE (-520 -855);
FORCEADD DNS..2
(-595 -830);
PAINT RED (-595 -830);
FORCEPROP 2 LAST CDS_LIB mstr_misc
J 0
(-595 -830);
PAINT ORANGE (-595 -830);
DISPLAY INVISIBLE (-595 -830);
FORCEPROP 1 LAST COMMENT_BODY TRUE
R 1
J 0
(-520 -1055);
DISPLAY 0.872340 (-520 -1055);
PAINT GREEN (-520 -1055);
DISPLAY INVISIBLE (-520 -1055);
FORCEADD DNS..2
(-595 -1080);
PAINT RED (-595 -1080);
FORCEPROP 2 LAST CDS_LIB mstr_misc
J 0
(-595 -1080);
PAINT ORANGE (-595 -1080);
DISPLAY INVISIBLE (-595 -1080);
FORCEPROP 1 LAST COMMENT_BODY TRUE
R 1
J 0
(-520 -1305);
DISPLAY 0.872340 (-520 -1305);
PAINT GREEN (-520 -1305);
DISPLAY INVISIBLE (-520 -1305);
FORCEADD DNS..2
(-595 -3480);
PAINT RED (-595 -3480);
FORCEPROP 2 LAST CDS_LIB mstr_misc
J 0
(-595 -3480);
PAINT ORANGE (-595 -3480);
DISPLAY INVISIBLE (-595 -3480);
FORCEPROP 1 LAST COMMENT_BODY TRUE
R 1
J 0
(-520 -3705);
DISPLAY 0.872340 (-520 -3705);
PAINT GREEN (-520 -3705);
DISPLAY INVISIBLE (-520 -3705);
FORCEADD DNS..2
(1855 -180);
PAINT RED (1855 -180);
FORCEPROP 2 LAST CDS_LIB mstr_misc
J 0
(1855 -180);
PAINT MONO (1855 -180);
DISPLAY INVISIBLE (1855 -180);
FORCEPROP 1 LAST COMMENT_BODY TRUE
R 1
J 0
(1930 -405);
DISPLAY 0.872340 (1930 -405);
PAINT GREEN (1930 -405);
DISPLAY INVISIBLE (1930 -405);
FORCEADD DNS..2
(-595 -1480);
PAINT RED (-595 -1480);
FORCEPROP 2 LAST CDS_LIB mstr_misc
J 0
(-595 -1480);
PAINT ORANGE (-595 -1480);
DISPLAY INVISIBLE (-595 -1480);
FORCEPROP 1 LAST COMMENT_BODY TRUE
R 1
J 0
(-520 -1705);
DISPLAY 0.872340 (-520 -1705);
PAINT GREEN (-520 -1705);
DISPLAY INVISIBLE (-520 -1705);
FORCEADD DNS..2
(-595 -380);
PAINT RED (-595 -380);
FORCEPROP 2 LAST CDS_LIB mstr_misc
J 0
(-595 -380);
PAINT ORANGE (-595 -380);
DISPLAY INVISIBLE (-595 -380);
FORCEPROP 1 LAST COMMENT_BODY TRUE
R 1
J 0
(-520 -605);
DISPLAY 0.872340 (-520 -605);
PAINT GREEN (-520 -605);
DISPLAY INVISIBLE (-520 -605);
FORCEADD DNS..2
(-595 -180);
PAINT RED (-595 -180);
FORCEPROP 2 LAST CDS_LIB mstr_misc
J 0
(-595 -180);
PAINT ORANGE (-595 -180);
DISPLAY INVISIBLE (-595 -180);
FORCEPROP 1 LAST COMMENT_BODY TRUE
R 1
J 0
(-520 -405);
DISPLAY 0.872340 (-520 -405);
PAINT GREEN (-520 -405);
DISPLAY INVISIBLE (-520 -405);
FORCEADD DNS..2
(-595 -2480);
PAINT RED (-595 -2480);
FORCEPROP 2 LAST CDS_LIB mstr_misc
J 0
(-595 -2480);
PAINT ORANGE (-595 -2480);
DISPLAY INVISIBLE (-595 -2480);
FORCEPROP 1 LAST COMMENT_BODY TRUE
R 1
J 0
(-520 -2705);
DISPLAY 0.872340 (-520 -2705);
PAINT GREEN (-520 -2705);
DISPLAY INVISIBLE (-520 -2705);
FORCEADD DNS..2
(1855 -380);
PAINT RED (1855 -380);
FORCEPROP 2 LAST CDS_LIB mstr_misc
J 0
(1855 -380);
PAINT ORANGE (1855 -380);
DISPLAY INVISIBLE (1855 -380);
FORCEPROP 1 LAST COMMENT_BODY TRUE
R 1
J 0
(1930 -605);
DISPLAY 0.872340 (1930 -605);
PAINT GREEN (1930 -605);
DISPLAY INVISIBLE (1930 -605);
FORCEADD DNS..2
(1855 420);
PAINT RED (1855 420);
FORCEPROP 2 LAST CDS_LIB mstr_misc
J 0
(1855 420);
PAINT ORANGE (1855 420);
DISPLAY INVISIBLE (1855 420);
FORCEPROP 1 LAST COMMENT_BODY TRUE
R 1
J 0
(1930 195);
DISPLAY 0.872340 (1930 195);
PAINT GREEN (1930 195);
DISPLAY INVISIBLE (1930 195);
FORCEADD INTEL_CORP_BPAGE..1
(6750 -4275);
FORCEPROP 1 LAST CDS_CON_LAST_MODIFIED Fri Jun 16 17:48:56 2017
J 0
(5325 -3950);
DISPLAY 1.361702 (5325 -3950);
PAINT GREEN (5325 -3950);
DISPLAY INVISIBLE (5325 -3950);
FORCEPROP 2 LAST CUSTOM_TXT_CDS <XR_PAGE_TITLE>
J 0
(-1140 975);
DISPLAY 0.638298 (-1140 975);
PAINT PINK (-1140 975);
DISPLAY INVISIBLE (-1140 975);
FORCEPROP 2 LAST CUSTOM_TXT_CDS <CON_LAST_MODIFIED>
J 0
(2750 -4175);
PAINT ORANGE (2750 -4175);
FORCEPROP 2 LAST CUSTOM_TXT_CDS <CURRENT_DESIGN_SHEET> OF <TOTAL_DESIGN_SHEETS>
J 0
(6250 -4250);
PAINT ORANGE (6250 -4250);
FORCEPROP 1 LAST SCH_TITLE BMC STRAPS
J 0
(-1200 -4225);
DISPLAY 1.212766 (-1200 -4225);
PAINT ORANGE (-1200 -4225);
FORCEPROP 2 LAST CDS_XR_PAGE_TITLE CR-150 : @BASEBOARD_FAB2_LIB.BASEBOARD_FAB2(SCH_1):PAGE150
J 0
(-1140 975);
DISPLAY 0.638298 (-1140 975);
PAINT PINK (-1140 975);
DISPLAY INVISIBLE (-1140 975);
FORCEPROP 2 LAST PAGE_BORDER TRUE
J 0
(-1140 975);
DISPLAY 0.851064 (-1140 975);
PAINT PINK (-1140 975);
DISPLAY INVISIBLE (-1140 975);
FORCEPROP 2 LAST CDS_LIB mstr_symbols
J 0
(6750 -4275);
DISPLAY 1.361702 (6750 -4275);
PAINT ORANGE (6750 -4275);
DISPLAY INVISIBLE (6750 -4275);
FORCEPROP 1 LAST COMMENT_BODY TRUE
J 0
(6762 -4263);
DISPLAY 0.617021 (6762 -4263);
PAINT GREEN (6762 -4263);
DISPLAY INVISIBLE (6762 -4263);
FORCEADD DNS..2
(-595 -2080);
PAINT RED (-595 -2080);
FORCEPROP 2 LAST CDS_LIB mstr_misc
J 0
(-595 -2080);
PAINT ORANGE (-595 -2080);
DISPLAY INVISIBLE (-595 -2080);
FORCEPROP 1 LAST COMMENT_BODY TRUE
R 1
J 0
(-520 -2305);
DISPLAY 0.872340 (-520 -2305);
PAINT GREEN (-520 -2305);
DISPLAY INVISIBLE (-520 -2305);
FORCEADD DNS..2
(1855 -980);
PAINT RED (1855 -980);
FORCEPROP 2 LAST CDS_LIB mstr_misc
J 0
(1855 -980);
PAINT ORANGE (1855 -980);
DISPLAY INVISIBLE (1855 -980);
FORCEPROP 1 LAST COMMENT_BODY TRUE
R 1
J 0
(1930 -1205);
DISPLAY 0.872340 (1930 -1205);
PAINT GREEN (1930 -1205);
DISPLAY INVISIBLE (1930 -1205);
FORCEADD DNS..2
(-595 -2880);
PAINT RED (-595 -2880);
FORCEPROP 1 LAST COMMENT_BODY TRUE
R 1
J 0
(-520 -3105);
DISPLAY 0.872340 (-520 -3105);
PAINT GREEN (-520 -3105);
DISPLAY INVISIBLE (-520 -3105);
FORCEPROP 2 LAST CDS_LIB mstr_misc
J 0
(-595 -2880);
DISPLAY INVISIBLE (-595 -2880);
FORCEADD DNS..2
(1855 -780);
PAINT RED (1855 -780);
FORCEPROP 1 LAST COMMENT_BODY TRUE
R 1
J 0
(1930 -1005);
DISPLAY 0.872340 (1930 -1005);
PAINT GREEN (1930 -1005);
DISPLAY INVISIBLE (1930 -1005);
FORCEPROP 2 LAST CDS_LIB mstr_misc
J 0
(1855 -780);
DISPLAY INVISIBLE (1855 -780);
FORCEADD DNS..2
(-595 -3080);
PAINT RED (-595 -3080);
FORCEPROP 1 LAST COMMENT_BODY TRUE
R 1
J 0
(-520 -3305);
DISPLAY 0.872340 (-520 -3305);
PAINT GREEN (-520 -3305);
DISPLAY INVISIBLE (-520 -3305);
FORCEPROP 2 LAST CDS_LIB mstr_misc
J 0
(-595 -3080);
PAINT ORANGE (-595 -3080);
DISPLAY INVISIBLE (-595 -3080);
WIRE 16 -1 (-1000 200)(-1000 500);
WIRE 16 -1 (-1000 200)(-1000 0);
WIRE 16 -1 (-700 200)(-1000 200);
WIRE 16 -1 (-1000 -200)(-1000 0);
WIRE 16 -1 (-700 0)(-1000 0);
WIRE 16 -1 (-1000 -400)(-1000 -200);
WIRE 16 -1 (-700 -200)(-1000 -200);
WIRE 16 -1 (-1000 -650)(-1000 -400);
WIRE 16 -1 (-1000 -400)(-700 -400);
WIRE 16 -1 (-1000 -1100)(-1000 -650);
WIRE 16 -1 (-700 -650)(-1000 -650);
WIRE 16 -1 (-1000 -1500)(-1000 -1100);
WIRE 16 -1 (-700 -1100)(-1000 -1100);
WIRE 16 -1 (-1000 -1900)(-1000 -1500);
WIRE 16 -1 (-700 -1500)(-1000 -1500);
WIRE 16 -1 (-1000 -1900)(-1000 -2100);
WIRE 16 -1 (-700 -1900)(-1000 -1900);
WIRE 16 -1 (-1000 -2100)(-1000 -2500);
WIRE 16 -1 (-700 -2100)(-1000 -2100);
WIRE 16 -1 (-1000 -2900)(-1000 -2500);
WIRE 16 -1 (-700 -2500)(-1000 -2500);
WIRE 16 -1 (-1000 -2900)(-1000 -3100);
WIRE 16 -1 (-700 -2900)(-1000 -2900);
WIRE 16 -1 (-1000 -3100)(-1000 -3500);
WIRE 16 -1 (-700 -3100)(-1000 -3100);
WIRE 16 -1 (-700 -3500)(-1000 -3500);
WIRE 16 -1 (-900 -850)(-900 -900);
WIRE 16 -1 (-700 -850)(-900 -850);
WIRE 16 -1 (-900 -1300)(-900 -1350);
WIRE 16 -1 (-700 -1300)(-900 -1300);
WIRE 16 -1 (-900 -2300)(-900 -2350);
WIRE 16 -1 (-700 -2300)(-900 -2300);
WIRE 16 -1 (-900 -2700)(-900 -2750);
WIRE 16 -1 (-700 -2700)(-900 -2700);
WIRE 16 -1 (-900 -3300)(-900 -3350);
WIRE 16 -1 (-700 -3300)(-900 -3300);
WIRE 16 -1 (-900 -3650)(-900 -3700);
WIRE 16 -1 (-700 -3650)(-900 -3650);
WIRE 16 -1 (1550 200)(1550 150);
WIRE 16 -1 (1750 200)(1550 200);
WIRE 16 -1 (1450 500)(1450 400);
WIRE 16 -1 (1450 0)(1450 400);
WIRE 16 -1 (1750 400)(1450 400);
WIRE 16 -1 (1450 0)(1450 -200);
WIRE 16 -1 (1750 0)(1450 0);
WIRE 16 -1 (1450 -200)(1450 -400);
WIRE 16 -1 (1750 -200)(1450 -200);
WIRE 16 -1 (1450 -400)(1450 -600);
WIRE 16 -1 (1450 -400)(1750 -400);
WIRE 16 -1 (1450 -600)(1450 -800);
WIRE 16 -1 (1750 -600)(1450 -600);
WIRE 16 -1 (1450 -800)(1450 -1000);
WIRE 16 -1 (1450 -800)(1750 -800);
WIRE 16 -1 (1450 -1000)(1450 -1200);
WIRE 16 -1 (1750 -1000)(1450 -1000);
WIRE 16 -1 (1450 -1200)(1450 -1400);
WIRE 16 -1 (1450 -1200)(1750 -1200);
WIRE 16 -1 (1750 -1400)(1450 -1400);
WIRE 16 -1 (-500 -2900)(800 -2900);
FORCEPROP 2 LAST SIG_NAME TP_RGMII1TXD3_GPIOT5
J 0
(-35 -2890);
DISPLAY 0.638298 (-35 -2890);
PAINT ORANGE (-35 -2890);
WIRE 16 -1 (-50 -2700)(-500 -2700);
WIRE 16 -1 (-50 -2500)(-50 -2700);
WIRE 16 -1 (-50 -2500)(-500 -2500);
WIRE 16 -1 (800 -2500)(-50 -2500);
FORCEPROP 2 LAST SIG_NAME TP_RGMII1TXD2_GPIOT4
J 0
(-35 -2490);
DISPLAY 0.638298 (-35 -2490);
PAINT ORANGE (-35 -2490);
WIRE 16 -1 (-50 -3300)(-500 -3300);
WIRE 16 -1 (-50 -3100)(-500 -3100);
WIRE 16 -1 (-50 -3100)(-50 -3300);
WIRE 16 -1 (800 -3100)(-50 -3100);
FORCEPROP 2 LAST SIG_NAME RMII_BMC_PCH_SPRNGVLLE_TXD0_R
J 0
(-35 -3090);
DISPLAY 0.638298 (-35 -3090);
PAINT ORANGE (-35 -3090);
WIRE 16 -1 (-50 -2300)(-500 -2300);
WIRE 16 -1 (-50 -2100)(-500 -2100);
WIRE 16 -1 (-50 -2100)(-50 -2300);
WIRE 16 -1 (800 -2100)(-50 -2100);
FORCEPROP 2 LAST SIG_NAME RMII_BMC_OCP_TXD1_R
J 0
(-35 -2090);
DISPLAY 0.638298 (-35 -2090);
PAINT ORANGE (-35 -2090);
WIRE 16 -1 (3100 -800)(1950 -800);
FORCEPROP 2 LAST SIG_NAME BMC_STRAP_BIT17
J 0
(2415 -790);
DISPLAY 0.638298 (2415 -790);
PAINT ORANGE (2415 -790);
WIRE 16 -1 (1950 -600)(3100 -600);
FORCEPROP 2 LAST SIG_NAME GPIOS7
J 0
(2415 -590);
DISPLAY 0.638298 (2415 -590);
PAINT ORANGE (2415 -590);
WIRE 16 -1 (1950 -1400)(3100 -1400);
FORCEPROP 2 LAST SIG_NAME BMC_STRAP_BIT27
J 0
(2415 -1390);
DISPLAY 0.638298 (2415 -1390);
PAINT ORANGE (2415 -1390);
WIRE 16 -1 (3100 -1200)(1950 -1200);
FORCEPROP 2 LAST SIG_NAME BMC_STRAP_BIT20
J 0
(2415 -1190);
DISPLAY 0.638298 (2415 -1190);
PAINT ORANGE (2415 -1190);
WIRE 16 -1 (1950 -1000)(3100 -1000);
FORCEPROP 2 LAST SIG_NAME BMC_STRAP_BIT18
J 0
(2415 -990);
DISPLAY 0.638298 (2415 -990);
PAINT ORANGE (2415 -990);
WIRE 16 -1 (3100 -400)(1950 -400);
FORCEPROP 2 LAST SIG_NAME BMC_STRAP_BIT5
J 0
(2415 -390);
DISPLAY 0.638298 (2415 -390);
PAINT ORANGE (2415 -390);
WIRE 16 -1 (1950 -200)(3100 -200);
FORCEPROP 2 LAST SIG_NAME BMC_STRAP_BIT3
J 0
(2415 -190);
DISPLAY 0.638298 (2415 -190);
PAINT ORANGE (2415 -190);
WIRE 16 -1 (-500 0)(800 0);
FORCEPROP 2 LAST SIG_NAME SPI_BMC_BT_DO
J 0
(-35 10);
DISPLAY 0.638298 (-35 10);
PAINT ORANGE (-35 10);
WIRE 16 -1 (2400 200)(1950 200);
WIRE 16 -1 (2400 400)(1950 400);
WIRE 16 -1 (2400 400)(2400 200);
WIRE 16 -1 (3100 400)(2400 400);
FORCEPROP 2 LAST SIG_NAME TP_RGMII2TXD2_GPIOU2
J 0
(2415 410);
DISPLAY 0.638298 (2415 410);
PAINT ORANGE (2415 410);
WIRE 16 -1 (3100 0)(1950 0);
FORCEPROP 2 LAST SIG_NAME TP_RGMII2TXD3_GPIOU3
J 0
(2415 10);
DISPLAY 0.638298 (2415 10);
PAINT ORANGE (2415 10);
WIRE 16 -1 (-50 -3650)(-500 -3650);
WIRE 16 -1 (-50 -3500)(-50 -3650);
WIRE 16 -1 (-50 -3500)(-500 -3500);
WIRE 16 -1 (800 -3500)(-50 -3500);
FORCEPROP 2 LAST SIG_NAME RMII_BMC_PCH_SPRNGVLLE_TXD1_R
J 0
(-35 -3490);
DISPLAY 0.638298 (-35 -3490);
PAINT ORANGE (-35 -3490);
WIRE 16 -1 (-500 -1500)(800 -1500);
FORCEPROP 2 LAST SIG_NAME RMII_BMC_PCH_SPRNGVLLE_TXEN
J 0
(-35 -1490);
DISPLAY 0.638298 (-35 -1490);
PAINT ORANGE (-35 -1490);
WIRE 16 -1 (-500 -1900)(800 -1900);
FORCEPROP 2 LAST SIG_NAME RMII_BMC_OCP_TXD0_R
J 0
(-35 -1890);
DISPLAY 0.638298 (-35 -1890);
PAINT ORANGE (-35 -1890);
WIRE 16 -1 (-50 -1300)(-500 -1300);
WIRE 16 -1 (-50 -1100)(-500 -1100);
WIRE 16 -1 (-50 -1100)(-50 -1300);
WIRE 16 -1 (800 -1100)(-50 -1100);
FORCEPROP 2 LAST SIG_NAME RMII_BMC_OCP_TXEN
J 0
(-35 -1090);
DISPLAY 0.638298 (-35 -1090);
PAINT ORANGE (-35 -1090);
WIRE 16 -1 (-500 -850)(-50 -850);
WIRE 16 -1 (-500 -650)(-50 -650);
WIRE 16 -1 (-50 -850)(-50 -650);
WIRE 16 -1 (-50 -650)(800 -650);
FORCEPROP 2 LAST SIG_NAME UART_BMC_TXD5
J 0
(-35 -640);
DISPLAY 0.638298 (-35 -640);
PAINT ORANGE (-35 -640);
WIRE 16 -1 (800 -400)(-500 -400);
FORCEPROP 2 LAST SIG_NAME PU_JTAG_BMC_RTCK
J 0
(-35 -390);
DISPLAY 0.638298 (-35 -390);
PAINT ORANGE (-35 -390);
WIRE 16 -1 (800 -200)(-500 -200);
FORCEPROP 2 LAST SIG_NAME SPI_BMC_BT_DI
J 0
(-35 -190);
DISPLAY 0.638298 (-35 -190);
PAINT ORANGE (-35 -190);
WIRE 16 -1 (-500 200)(800 200);
FORCEPROP 2 LAST SIG_NAME SPI_BMC_BT_CLK
J 0
(-35 210);
DISPLAY 0.638298 (-35 210);
PAINT ORANGE (-35 210);
DOT 1 (1450 -600);
DOT 1 (1450 0);
DOT 1 (1450 -200);
DOT 1 (1450 -400);
DOT 1 (1450 400);
DOT 1 (-1000 -400);
DOT 1 (-1000 -200);
DOT 1 (-1000 0);
DOT 1 (-1000 200);
DOT 1 (2400 400);
DOT 1 (1450 -1200);
DOT 1 (1450 -1000);
DOT 1 (1450 -800);
DOT 1 (-50 -650);
DOT 1 (-1000 -650);
DOT 1 (-1000 -3100);
DOT 1 (-1000 -2900);
DOT 1 (-50 -3500);
DOT 1 (-50 -3100);
DOT 1 (-1000 -2500);
DOT 1 (-1000 -2100);
DOT 1 (-1000 -1900);
DOT 1 (-50 -2500);
DOT 1 (-50 -2100);
DOT 1 (-1000 -1500);
DOT 1 (-1000 -1100);
DOT 1 (-50 -1100);
FORCENOTE
TP FAB1 NOPOP RES 0227
(2250 -950) 0;
DISPLAY LEFT (2250 -950);
DISPLAY 0.638298 (2250 -950);
PAINT RED (2250 -950);
FORCENOTE
BIT:[15]
(3150 -550) 0;
DISPLAY LEFT (3150 -550);
DISPLAY 1.021277 (3150 -550);
PAINT PURPLE (3150 -550);
FORCENOTE
BIT:[20]
(3150 -1150) 0;
DISPLAY LEFT (3150 -1150);
DISPLAY 1.021277 (3150 -1150);
PAINT PURPLE (3150 -1150);
FORCENOTE
TP FAB3 ADD R25W156 0803
(-300 -550) 0;
DISPLAY LEFT (-300 -550);
DISPLAY 1.021277 (-300 -550);
PAINT RED (-300 -550);
FORCENOTE
BIT:[25]
(850 -150) 0;
DISPLAY LEFT (850 -150);
DISPLAY 1.021277 (850 -150);
PAINT PURPLE (850 -150);
FORCENOTE
BIT:[7]
(850 -1450) 0;
DISPLAY LEFT (850 -1450);
DISPLAY 1.021277 (850 -1450);
PAINT PURPLE (850 -1450);
FORCENOTE
TP FAB1 THIS PIN ALREADY HAS PD RES R9E13 IN PAGE 139
(-850 -1650) 0;
DISPLAY LEFT (-850 -1650);
DISPLAY 1.021277 (-850 -1650);
PAINT PINK (-850 -1650);
FORCENOTE
BIT:[3]
(3150 -150) 0;
DISPLAY LEFT (3150 -150);
DISPLAY 1.021277 (3150 -150);
PAINT PURPLE (3150 -150);
FORCENOTE
BIT:[23]
(3150 450) 0;
DISPLAY LEFT (3150 450);
DISPLAY 1.021277 (3150 450);
PAINT PURPLE (3150 450);
FORCENOTE
BIT:[17]
(3150 -750) 0;
DISPLAY LEFT (3150 -750);
DISPLAY 1.021277 (3150 -750);
PAINT PURPLE (3150 -750);
FORCENOTE
BIT:[30]
(850 250) 0;
DISPLAY LEFT (850 250);
DISPLAY 1.021277 (850 250);
PAINT PURPLE (850 250);
FORCENOTE
BIT:[24]
(3150 50) 0;
DISPLAY LEFT (3150 50);
DISPLAY 1.021277 (3150 50);
PAINT PURPLE (3150 50);
FORCENOTE
TP FAB1 ADD PD RES 0227
(2300 175) 0;
DISPLAY LEFT (2300 175);
DISPLAY 1.021277 (2300 175);
PAINT RED (2300 175);
FORCENOTE
TP FAB1 NOPOP RES 0227
(2250 450) 0;
DISPLAY LEFT (2250 450);
DISPLAY 1.021277 (2250 450);
PAINT RED (2250 450);
FORCENOTE
BIT:[5]
(3150 -350) 0;
DISPLAY LEFT (3150 -350);
DISPLAY 1.021277 (3150 -350);
PAINT PURPLE (3150 -350);
FORCENOTE
BIT:[31]
(850 50) 0;
DISPLAY LEFT (850 50);
DISPLAY 1.021277 (850 50);
PAINT PURPLE (850 50);
FORCENOTE
BIT:[0]
(850 450) 0;
DISPLAY LEFT (850 450);
DISPLAY 1.021277 (850 450);
PAINT PURPLE (850 450);
FORCENOTE
TP FAB1 THIS PIN ALREADY HAS POP PU  RES RN8F1 IN PAGE 246
(-875 650) 0;
DISPLAY LEFT (-875 650);
DISPLAY 1.021277 (-875 650);
PAINT PINK (-875 650);
FORCENOTE
BIT:[29]
(850 -600) 0;
DISPLAY LEFT (850 -600);
DISPLAY 1.021277 (850 -600);
PAINT PURPLE (850 -600);
FORCENOTE
TP FAB1 POP RES 0227
(2225 50) 0;
DISPLAY LEFT (2225 50);
DISPLAY 1.021277 (2225 50);
PAINT RED (2225 50);
FORCENOTE
BOM_COST=SM_MEM
(-1215 -4104) 0;
DISPLAY LEFT (-1215 -4104);
DISPLAY 0.765957 (-1215 -4104);
PAINT PURPLE (-1215 -4104);
FORCENOTE
BIT:[13]
(850 -2050) 0;
DISPLAY LEFT (850 -2050);
DISPLAY 1.021277 (850 -2050);
PAINT PURPLE (850 -2050);
FORCENOTE
BIT:[22]
(850 -3450) 0;
DISPLAY LEFT (850 -3450);
DISPLAY 1.021277 (850 -3450);
PAINT PURPLE (850 -3450);
FORCENOTE
BIT:[21]
(850 -3050) 0;
DISPLAY LEFT (850 -3050);
DISPLAY 1.021277 (850 -3050);
PAINT PURPLE (850 -3050);
FORCENOTE
BIT:[12]
(850 -1850) 0;
DISPLAY LEFT (850 -1850);
DISPLAY 1.021277 (850 -1850);
PAINT PURPLE (850 -1850);
FORCENOTE
BIT:[6]
(850 -1050) 0;
DISPLAY LEFT (850 -1050);
DISPLAY 1.021277 (850 -1050);
PAINT PURPLE (850 -1050);
FORCENOTE
TP FAB1 NOPOP RES 0104
(-25 -900) 0;
DISPLAY LEFT (-25 -900);
DISPLAY 1.021277 (-25 -900);
PAINT RED (-25 -900);
FORCENOTE
TP FAB1 ADD PD RES 0227
(0 -1325) 0;
DISPLAY LEFT (0 -1325);
DISPLAY 1.021277 (0 -1325);
PAINT RED (0 -1325);
FORCENOTE
TP FAB1 POP RES 0104
(-200 -1850) 0;
DISPLAY LEFT (-200 -1850);
DISPLAY 1.021277 (-200 -1850);
PAINT RED (-200 -1850);
FORCENOTE
TP FAB1 ADD PD RES 0227
(0 -3325) 0;
DISPLAY LEFT (0 -3325);
DISPLAY 1.021277 (0 -3325);
PAINT RED (0 -3325);
FORCENOTE
BIT:[26]
(850 -350) 0;
DISPLAY LEFT (850 -350);
DISPLAY 1.021277 (850 -350);
PAINT PURPLE (850 -350);
FORCENOTE
TP FAB1 STRPA BIT[0] SPI_BMC_BT_CS0_N RES IS MOVED TO PAGE 137 0308
(-875 500) 0;
DISPLAY LEFT (-875 500);
DISPLAY 1.021277 (-875 500);
PAINT RED (-875 500);
FORCENOTE
TP FAB1 POP R25W101 0217
(2250 -700) 0;
DISPLAY LEFT (2250 -700);
DISPLAY 0.638298 (2250 -700);
PAINT RED (2250 -700);
FORCENOTE
TP FAB4 NOPOP R25W101 20170124
(2250 -750) 0;
DISPLAY LEFT (2250 -750);
DISPLAY 0.638298 (2250 -750);
PAINT RED (2250 -750);
FORCENOTE
BIT:[18]
(3150 -950) 0;
DISPLAY LEFT (3150 -950);
DISPLAY 1.021277 (3150 -950);
PAINT PURPLE (3150 -950);
FORCENOTE
BIT:[27]
(3150 -1350) 0;
DISPLAY LEFT (3150 -1350);
DISPLAY 1.021277 (3150 -1350);
PAINT PURPLE (3150 -1350);
FORCENOTE
TP FAB1 RENAME RGMII2TX2, TX3 0227
(2250 500) 0;
DISPLAY LEFT (2250 500);
DISPLAY 1.021277 (2250 500);
PAINT RED (2250 500);
FORCENOTE
TP FAB1 NOPOP RES 0104
(-200 -2050) 0;
DISPLAY LEFT (-200 -2050);
DISPLAY 1.021277 (-200 -2050);
PAINT RED (-200 -2050);
FORCENOTE
BIT:[16]
(850 -2450) 0;
DISPLAY LEFT (850 -2450);
DISPLAY 1.021277 (850 -2450);
PAINT PURPLE (850 -2450);
FORCENOTE
BIT:[19]
(850 -2850) 0;
DISPLAY LEFT (850 -2850);
DISPLAY 1.021277 (850 -2850);
PAINT PURPLE (850 -2850);
FORCENOTE
TP FAB1 ADD PD RES 0227
(0 -2725) 0;
DISPLAY LEFT (0 -2725);
DISPLAY 1.021277 (0 -2725);
PAINT RED (0 -2725);
FORCENOTE
TP FAB4 NOPOP R25W115 20170509
(-250 -2850) 0;
DISPLAY LEFT (-250 -2850);
DISPLAY 0.638298 (-250 -2850);
PAINT RED (-250 -2850);
FORCENOTE
$CDS_IMAGE|image1.jpg|3175|4500
(5150 -1625) 0;
DISPLAY LEFT (5150 -1625);
QUIT
